FILE_TYPE = MACRO_DRAWING;
SET COLOR_WIRE YELLOW;
SET COLOR_PROP ORANGE;
SET COLOR_DOT WHITE;
SET COLOR_ARC YELLOW;
SET COLOR_BODY GREEN;
SET COLOR_NOTE PURPLE;
SET PROP_DISPLAY VALUE;
SET PAGE_NUMBER P40;
FORCEADD UNIVERSAL_GND..1
(-3675 -725);
FORCEPROP 3 LASTPIN (-3675 -675) SIG_NAME GND\g
J 0
(-3665 -665);
DISPLAY 0.659574 (-3665 -665);
PAINT MONO (-3665 -665);
DISPLAY INVISIBLE (-3665 -665);
FORCEPROP 2 LAST CDS_LIB logical_power
J 0
(-3675 -725);
PAINT MONO (-3675 -725);
DISPLAY INVISIBLE (-3675 -725);
FORCEPROP 1 LAST HDL_POWER GND
J 1
(-3650 -800);
DISPLAY 0.872340 (-3650 -800);
PAINT GREEN (-3650 -800);
DISPLAY INVISIBLE (-3650 -800);
FORCEPROP 1 LAST PATH I1
J 0
(-3600 -725);
DISPLAY 0.872340 (-3600 -725);
PAINT AQUA (-3600 -725);
DISPLAY INVISIBLE (-3600 -725);
FORCEADD SOCKET4677_AZIF0045P001C01CS..34
(-2225 1800);
FORCEPROP 1 LAST PART_NUMBER DGA^7000023
J 0
(-3275 4050);
DISPLAY 0.723404 (-3275 4050);
PAINT GREEN (-3275 4050);
DISPLAY INVISIBLE (-3275 4050);
FORCEPROP 2 LAST PART_TYPE SMLF
J 0
(-3275 4225);
DISPLAY 1.021277 (-3275 4225);
FORCEPROP 1 LAST MATERIAL IO
J 0
(-3275 3975);
DISPLAY 0.723404 (-3275 3975);
PAINT GREEN (-3275 3975);
FORCEPROP 2 LAST VALUE SOCKET4677_AZIF0045-P001C01CS
J 0
(-3275 4175);
DISPLAY 1.021277 (-3275 4175);
FORCEPROP 1 LAST $LOCATION U2
J 0
(-3275 4125);
DISPLAY 0.723404 (-3275 4125);
PAINT GREEN (-3275 4125);
FORCEPROP 0 LASTPIN (-1025 -175) $PN DB91
J 0
(-1015 -165);
DISPLAY 0.680851 (-1015 -165);
PAINT MONO (-1015 -165);
FORCEPROP 0 LASTPIN (-1025 -125) $PN DC1
J 0
(-1015 -115);
DISPLAY 0.680851 (-1015 -115);
PAINT MONO (-1015 -115);
FORCEPROP 0 LASTPIN (-1025 25) $PN DC13
J 0
(-1015 35);
DISPLAY 0.680851 (-1015 35);
PAINT MONO (-1015 35);
FORCEPROP 0 LASTPIN (-1025 75) $PN DC21
J 0
(-1015 85);
DISPLAY 0.680851 (-1015 85);
PAINT MONO (-1015 85);
FORCEPROP 0 LASTPIN (-1025 325) $PN DC52
J 0
(-1015 335);
DISPLAY 0.680851 (-1015 335);
PAINT MONO (-1015 335);
FORCEPROP 0 LASTPIN (-1025 375) $PN DC58
J 0
(-1015 385);
DISPLAY 0.680851 (-1015 385);
PAINT MONO (-1015 385);
FORCEPROP 0 LASTPIN (-1025 425) $PN DC64
J 0
(-1015 435);
DISPLAY 0.680851 (-1015 435);
PAINT MONO (-1015 435);
FORCEPROP 0 LASTPIN (-1025 875) $PN DD12
J 0
(-1015 885);
DISPLAY 0.680851 (-1015 885);
PAINT MONO (-1015 885);
FORCEPROP 0 LASTPIN (-1025 925) $PN DD16
J 0
(-1015 935);
DISPLAY 0.680851 (-1015 935);
PAINT MONO (-1015 935);
FORCEPROP 0 LASTPIN (-1025 975) $PN DD49
J 0
(-1015 985);
DISPLAY 0.680851 (-1015 985);
PAINT MONO (-1015 985);
FORCEPROP 0 LASTPIN (-1025 1625) $PN DE39
J 0
(-1015 1635);
DISPLAY 0.680851 (-1015 1635);
PAINT MONO (-1015 1635);
FORCEPROP 0 LASTPIN (-1025 2375) $PN DE70
J 0
(-1015 2385);
DISPLAY 0.680851 (-1015 2385);
PAINT MONO (-1015 2385);
FORCEPROP 0 LASTPIN (-1025 2825) $PN DF12
J 0
(-1015 2835);
DISPLAY 0.680851 (-1015 2835);
PAINT MONO (-1015 2835);
FORCEPROP 0 LASTPIN (-1025 2875) $PN DF16
J 0
(-1015 2885);
DISPLAY 0.680851 (-1015 2885);
PAINT MONO (-1015 2885);
FORCEPROP 0 LASTPIN (-1025 2925) $PN DF49
J 0
(-1015 2935);
DISPLAY 0.680851 (-1015 2935);
PAINT MONO (-1015 2935);
FORCEPROP 0 LASTPIN (-1025 3075) $PN DF91
J 0
(-1015 3085);
DISPLAY 0.680851 (-1015 3085);
PAINT MONO (-1015 3085);
FORCEPROP 0 LASTPIN (-1025 3125) $PN DG1
J 0
(-1015 3135);
DISPLAY 0.680851 (-1015 3135);
PAINT MONO (-1015 3135);
FORCEPROP 0 LASTPIN (-1025 3275) $PN DG13
J 0
(-1015 3285);
DISPLAY 0.680851 (-1015 3285);
PAINT MONO (-1015 3285);
FORCEPROP 0 LASTPIN (-1025 3325) $PN DG21
J 0
(-1015 3335);
DISPLAY 0.680851 (-1015 3335);
PAINT MONO (-1015 3335);
FORCEPROP 0 LASTPIN (-1025 3575) $PN DG52
J 0
(-1015 3585);
DISPLAY 0.680851 (-1015 3585);
PAINT MONO (-1015 3585);
FORCEPROP 0 LASTPIN (-1025 3625) $PN DG58
J 0
(-1015 3635);
DISPLAY 0.680851 (-1015 3635);
PAINT MONO (-1015 3635);
FORCEPROP 0 LASTPIN (-1025 3675) $PN DG64
J 0
(-1015 3685);
DISPLAY 0.680851 (-1015 3685);
PAINT MONO (-1015 3685);
FORCEPROP 0 LASTPIN (-3425 125) $PN DH16
J 2
(-3435 135);
DISPLAY 0.680851 (-3435 135);
PAINT MONO (-3435 135);
FORCEPROP 0 LASTPIN (-3425 175) $PN DH20
J 2
(-3435 185);
DISPLAY 0.680851 (-3435 185);
PAINT MONO (-3435 185);
FORCEPROP 0 LASTPIN (-3425 275) $PN DH26
J 2
(-3435 285);
DISPLAY 0.680851 (-3435 285);
PAINT MONO (-3435 285);
FORCEPROP 0 LASTPIN (-3425 425) $PN DH34
J 2
(-3435 435);
DISPLAY 0.680851 (-3435 435);
PAINT MONO (-3435 435);
FORCEPROP 0 LASTPIN (-3425 575) $PN DH44
J 2
(-3435 585);
DISPLAY 0.680851 (-3435 585);
PAINT MONO (-3435 585);
FORCEPROP 0 LASTPIN (-3425 675) $PN DH51
J 2
(-3435 685);
DISPLAY 0.680851 (-3435 685);
PAINT MONO (-3435 685);
FORCEPROP 0 LASTPIN (-3425 725) $PN DH53
J 2
(-3435 735);
DISPLAY 0.680851 (-3435 735);
PAINT MONO (-3435 735);
FORCEPROP 0 LASTPIN (-3425 825) $PN DH59
J 2
(-3435 835);
DISPLAY 0.680851 (-3435 835);
PAINT MONO (-3435 835);
FORCEPROP 0 LASTPIN (-3425 875) $PN DH63
J 2
(-3435 885);
DISPLAY 0.680851 (-3435 885);
PAINT MONO (-3435 885);
FORCEPROP 0 LASTPIN (-3425 975) $PN DH69
J 2
(-3435 985);
DISPLAY 0.680851 (-3435 985);
PAINT MONO (-3435 985);
FORCEPROP 0 LASTPIN (-3425 1075) $PN DH75
J 2
(-3435 1085);
DISPLAY 0.680851 (-3435 1085);
PAINT MONO (-3435 1085);
FORCEPROP 0 LASTPIN (-3425 1325) $PN DJ25
J 2
(-3435 1335);
DISPLAY 0.680851 (-3435 1335);
PAINT MONO (-3435 1335);
FORCEPROP 0 LASTPIN (-3425 1475) $PN DJ35
J 2
(-3435 1485);
DISPLAY 0.680851 (-3435 1485);
PAINT MONO (-3435 1485);
FORCEPROP 0 LASTPIN (-3425 1775) $PN DJ54
J 2
(-3435 1785);
DISPLAY 0.680851 (-3435 1785);
PAINT MONO (-3435 1785);
FORCEPROP 0 LASTPIN (-3425 1925) $PN DJ62
J 2
(-3435 1935);
DISPLAY 0.680851 (-3435 1935);
PAINT MONO (-3435 1935);
FORCEPROP 0 LASTPIN (-3425 2025) $PN DJ68
J 2
(-3435 2035);
DISPLAY 0.680851 (-3435 2035);
PAINT MONO (-3435 2035);
FORCEPROP 0 LASTPIN (-3425 2475) $PN DK12
J 2
(-3435 2485);
DISPLAY 0.680851 (-3435 2485);
PAINT MONO (-3435 2485);
FORCEPROP 0 LASTPIN (-3425 2575) $PN DK18
J 2
(-3435 2585);
DISPLAY 0.680851 (-3435 2585);
PAINT MONO (-3435 2585);
FORCEPROP 0 LASTPIN (-3425 2625) $PN DK24
J 2
(-3435 2635);
DISPLAY 0.680851 (-3435 2635);
PAINT MONO (-3435 2635);
FORCEPROP 0 LASTPIN (-3425 2775) $PN DK42
J 2
(-3435 2785);
DISPLAY 0.680851 (-3435 2785);
PAINT MONO (-3435 2785);
FORCEPROP 0 LASTPIN (-3425 2875) $PN DK55
J 2
(-3435 2885);
DISPLAY 0.680851 (-3435 2885);
PAINT MONO (-3435 2885);
FORCEPROP 0 LASTPIN (-3425 2925) $PN DK61
J 2
(-3435 2935);
DISPLAY 0.680851 (-3435 2935);
PAINT MONO (-3435 2935);
FORCEPROP 0 LASTPIN (-3425 2975) $PN DK67
J 2
(-3435 2985);
DISPLAY 0.680851 (-3435 2985);
PAINT MONO (-3435 2985);
FORCEPROP 0 LASTPIN (-3425 3375) $PN DL1
J 2
(-3435 3385);
DISPLAY 0.680851 (-3435 3385);
PAINT MONO (-3435 3385);
FORCEPROP 0 LASTPIN (-3425 3525) $PN DL13
J 2
(-3435 3535);
DISPLAY 0.680851 (-3435 3535);
PAINT MONO (-3435 3535);
FORCEPROP 0 LASTPIN (-3425 3575) $PN DL17
J 2
(-3435 3585);
DISPLAY 0.680851 (-3435 3585);
PAINT MONO (-3435 3585);
FORCEPROP 0 LASTPIN (-3425 3425) $PN DL5
J 2
(-3435 3435);
DISPLAY 0.680851 (-3435 3435);
PAINT MONO (-3435 3435);
FORCEPROP 0 LASTPIN (-3425 3675) $PN DL52
J 2
(-3435 3685);
DISPLAY 0.680851 (-3435 3685);
PAINT MONO (-3435 3685);
FORCEPROP 0 LASTPIN (-1025 125) $PN DC27
J 0
(-1015 135);
DISPLAY 0.680851 (-1015 135);
PAINT MONO (-1015 135);
FORCEPROP 0 LASTPIN (-1025 175) $PN DC33
J 0
(-1015 185);
DISPLAY 0.680851 (-1015 185);
PAINT MONO (-1015 185);
FORCEPROP 0 LASTPIN (-1025 225) $PN DC39
J 0
(-1015 235);
DISPLAY 0.680851 (-1015 235);
PAINT MONO (-1015 235);
FORCEPROP 0 LASTPIN (-1025 275) $PN DC45
J 0
(-1015 285);
DISPLAY 0.680851 (-1015 285);
PAINT MONO (-1015 285);
FORCEPROP 0 LASTPIN (-1025 -75) $PN DC5
J 0
(-1015 -65);
DISPLAY 0.680851 (-1015 -65);
PAINT MONO (-1015 -65);
FORCEPROP 0 LASTPIN (-1025 475) $PN DC70
J 0
(-1015 485);
DISPLAY 0.680851 (-1015 485);
PAINT MONO (-1015 485);
FORCEPROP 0 LASTPIN (-1025 525) $PN DC76
J 0
(-1015 535);
DISPLAY 0.680851 (-1015 535);
PAINT MONO (-1015 535);
FORCEPROP 0 LASTPIN (-1025 575) $PN DC78
J 0
(-1015 585);
DISPLAY 0.680851 (-1015 585);
PAINT MONO (-1015 585);
FORCEPROP 0 LASTPIN (-1025 625) $PN DC80
J 0
(-1015 635);
DISPLAY 0.680851 (-1015 635);
PAINT MONO (-1015 635);
FORCEPROP 0 LASTPIN (-1025 675) $PN DC84
J 0
(-1015 685);
DISPLAY 0.680851 (-1015 685);
PAINT MONO (-1015 685);
FORCEPROP 0 LASTPIN (-1025 725) $PN DC88
J 0
(-1015 735);
DISPLAY 0.680851 (-1015 735);
PAINT MONO (-1015 735);
FORCEPROP 0 LASTPIN (-1025 -25) $PN DC9
J 0
(-1015 -15);
DISPLAY 0.680851 (-1015 -15);
PAINT MONO (-1015 -15);
FORCEPROP 0 LASTPIN (-1025 775) $PN DD4
J 0
(-1015 785);
DISPLAY 0.680851 (-1015 785);
PAINT MONO (-1015 785);
FORCEPROP 0 LASTPIN (-1025 1025) $PN DD79
J 0
(-1015 1035);
DISPLAY 0.680851 (-1015 1035);
PAINT MONO (-1015 1035);
FORCEPROP 0 LASTPIN (-1025 825) $PN DD8
J 0
(-1015 835);
DISPLAY 0.680851 (-1015 835);
PAINT MONO (-1015 835);
FORCEPROP 0 LASTPIN (-1025 1075) $PN DE17
J 0
(-1015 1085);
DISPLAY 0.680851 (-1015 1085);
PAINT MONO (-1015 1085);
FORCEPROP 0 LASTPIN (-1025 1125) $PN DE19
J 0
(-1015 1135);
DISPLAY 0.680851 (-1015 1135);
PAINT MONO (-1015 1135);
FORCEPROP 0 LASTPIN (-1025 1175) $PN DE21
J 0
(-1015 1185);
DISPLAY 0.680851 (-1015 1185);
PAINT MONO (-1015 1185);
FORCEPROP 0 LASTPIN (-1025 1225) $PN DE23
J 0
(-1015 1235);
DISPLAY 0.680851 (-1015 1235);
PAINT MONO (-1015 1235);
FORCEPROP 0 LASTPIN (-1025 1275) $PN DE25
J 0
(-1015 1285);
DISPLAY 0.680851 (-1015 1285);
PAINT MONO (-1015 1285);
FORCEPROP 0 LASTPIN (-1025 1325) $PN DE27
J 0
(-1015 1335);
DISPLAY 0.680851 (-1015 1335);
PAINT MONO (-1015 1335);
FORCEPROP 0 LASTPIN (-1025 1375) $PN DE29
J 0
(-1015 1385);
DISPLAY 0.680851 (-1015 1385);
PAINT MONO (-1015 1385);
FORCEPROP 0 LASTPIN (-1025 1425) $PN DE31
J 0
(-1015 1435);
DISPLAY 0.680851 (-1015 1435);
PAINT MONO (-1015 1435);
FORCEPROP 0 LASTPIN (-1025 1475) $PN DE33
J 0
(-1015 1485);
DISPLAY 0.680851 (-1015 1485);
PAINT MONO (-1015 1485);
FORCEPROP 0 LASTPIN (-1025 1525) $PN DE35
J 0
(-1015 1535);
DISPLAY 0.680851 (-1015 1535);
PAINT MONO (-1015 1535);
FORCEPROP 0 LASTPIN (-1025 1575) $PN DE37
J 0
(-1015 1585);
DISPLAY 0.680851 (-1015 1585);
PAINT MONO (-1015 1585);
FORCEPROP 0 LASTPIN (-1025 1675) $PN DE41
J 0
(-1015 1685);
DISPLAY 0.680851 (-1015 1685);
PAINT MONO (-1015 1685);
FORCEPROP 0 LASTPIN (-1025 1725) $PN DE43
J 0
(-1015 1735);
DISPLAY 0.680851 (-1015 1735);
PAINT MONO (-1015 1735);
FORCEPROP 0 LASTPIN (-1025 1775) $PN DE45
J 0
(-1015 1785);
DISPLAY 0.680851 (-1015 1785);
PAINT MONO (-1015 1785);
FORCEPROP 0 LASTPIN (-1025 1825) $PN DE48
J 0
(-1015 1835);
DISPLAY 0.680851 (-1015 1835);
PAINT MONO (-1015 1835);
FORCEPROP 0 LASTPIN (-1025 1875) $PN DE50
J 0
(-1015 1885);
DISPLAY 0.680851 (-1015 1885);
PAINT MONO (-1015 1885);
FORCEPROP 0 LASTPIN (-1025 1925) $PN DE52
J 0
(-1015 1935);
DISPLAY 0.680851 (-1015 1935);
PAINT MONO (-1015 1935);
FORCEPROP 0 LASTPIN (-1025 1975) $PN DE54
J 0
(-1015 1985);
DISPLAY 0.680851 (-1015 1985);
PAINT MONO (-1015 1985);
FORCEPROP 0 LASTPIN (-1025 2025) $PN DE56
J 0
(-1015 2035);
DISPLAY 0.680851 (-1015 2035);
PAINT MONO (-1015 2035);
FORCEPROP 0 LASTPIN (-1025 2075) $PN DE58
J 0
(-1015 2085);
DISPLAY 0.680851 (-1015 2085);
PAINT MONO (-1015 2085);
FORCEPROP 0 LASTPIN (-1025 2125) $PN DE60
J 0
(-1015 2135);
DISPLAY 0.680851 (-1015 2135);
PAINT MONO (-1015 2135);
FORCEPROP 0 LASTPIN (-1025 2175) $PN DE62
J 0
(-1015 2185);
DISPLAY 0.680851 (-1015 2185);
PAINT MONO (-1015 2185);
FORCEPROP 0 LASTPIN (-1025 2225) $PN DE64
J 0
(-1015 2235);
DISPLAY 0.680851 (-1015 2235);
PAINT MONO (-1015 2235);
FORCEPROP 0 LASTPIN (-1025 2275) $PN DE66
J 0
(-1015 2285);
DISPLAY 0.680851 (-1015 2285);
PAINT MONO (-1015 2285);
FORCEPROP 0 LASTPIN (-1025 2325) $PN DE68
J 0
(-1015 2335);
DISPLAY 0.680851 (-1015 2335);
PAINT MONO (-1015 2335);
FORCEPROP 0 LASTPIN (-1025 2425) $PN DE72
J 0
(-1015 2435);
DISPLAY 0.680851 (-1015 2435);
PAINT MONO (-1015 2435);
FORCEPROP 0 LASTPIN (-1025 2475) $PN DE74
J 0
(-1015 2485);
DISPLAY 0.680851 (-1015 2485);
PAINT MONO (-1015 2485);
FORCEPROP 0 LASTPIN (-1025 2525) $PN DE76
J 0
(-1015 2535);
DISPLAY 0.680851 (-1015 2535);
PAINT MONO (-1015 2535);
FORCEPROP 0 LASTPIN (-1025 2575) $PN DE82
J 0
(-1015 2585);
DISPLAY 0.680851 (-1015 2585);
PAINT MONO (-1015 2585);
FORCEPROP 0 LASTPIN (-1025 2625) $PN DE84
J 0
(-1015 2635);
DISPLAY 0.680851 (-1015 2635);
PAINT MONO (-1015 2635);
FORCEPROP 0 LASTPIN (-1025 2675) $PN DE88
J 0
(-1015 2685);
DISPLAY 0.680851 (-1015 2685);
PAINT MONO (-1015 2685);
FORCEPROP 0 LASTPIN (-1025 2725) $PN DF4
J 0
(-1015 2735);
DISPLAY 0.680851 (-1015 2735);
PAINT MONO (-1015 2735);
FORCEPROP 0 LASTPIN (-1025 2975) $PN DF79
J 0
(-1015 2985);
DISPLAY 0.680851 (-1015 2985);
PAINT MONO (-1015 2985);
FORCEPROP 0 LASTPIN (-1025 2775) $PN DF8
J 0
(-1015 2785);
DISPLAY 0.680851 (-1015 2785);
PAINT MONO (-1015 2785);
FORCEPROP 0 LASTPIN (-1025 3025) $PN DF87
J 0
(-1015 3035);
DISPLAY 0.680851 (-1015 3035);
PAINT MONO (-1015 3035);
FORCEPROP 0 LASTPIN (-1025 3375) $PN DG27
J 0
(-1015 3385);
DISPLAY 0.680851 (-1015 3385);
PAINT MONO (-1015 3385);
FORCEPROP 0 LASTPIN (-1025 3425) $PN DG33
J 0
(-1015 3435);
DISPLAY 0.680851 (-1015 3435);
PAINT MONO (-1015 3435);
FORCEPROP 0 LASTPIN (-1025 3475) $PN DG39
J 0
(-1015 3485);
DISPLAY 0.680851 (-1015 3485);
PAINT MONO (-1015 3485);
FORCEPROP 0 LASTPIN (-1025 3525) $PN DG45
J 0
(-1015 3535);
DISPLAY 0.680851 (-1015 3535);
PAINT MONO (-1015 3535);
FORCEPROP 0 LASTPIN (-1025 3175) $PN DG5
J 0
(-1015 3185);
DISPLAY 0.680851 (-1015 3185);
PAINT MONO (-1015 3185);
FORCEPROP 0 LASTPIN (-1025 3725) $PN DG70
J 0
(-1015 3735);
DISPLAY 0.680851 (-1015 3735);
PAINT MONO (-1015 3735);
FORCEPROP 0 LASTPIN (-1025 3775) $PN DG76
J 0
(-1015 3785);
DISPLAY 0.680851 (-1015 3785);
PAINT MONO (-1015 3785);
FORCEPROP 0 LASTPIN (-3425 -175) $PN DG80
J 2
(-3435 -165);
DISPLAY 0.680851 (-3435 -165);
PAINT MONO (-3435 -165);
FORCEPROP 0 LASTPIN (-3425 -125) $PN DG84
J 2
(-3435 -115);
DISPLAY 0.680851 (-3435 -115);
PAINT MONO (-3435 -115);
FORCEPROP 0 LASTPIN (-3425 -75) $PN DG88
J 2
(-3435 -65);
DISPLAY 0.680851 (-3435 -65);
PAINT MONO (-3435 -65);
FORCEPROP 0 LASTPIN (-1025 3225) $PN DG9
J 0
(-1015 3235);
DISPLAY 0.680851 (-1015 3235);
PAINT MONO (-1015 3235);
FORCEPROP 0 LASTPIN (-3425 75) $PN DH12
J 2
(-3435 85);
DISPLAY 0.680851 (-3435 85);
PAINT MONO (-3435 85);
FORCEPROP 0 LASTPIN (-3425 225) $PN DH22
J 2
(-3435 235);
DISPLAY 0.680851 (-3435 235);
PAINT MONO (-3435 235);
FORCEPROP 0 LASTPIN (-3425 325) $PN DH28
J 2
(-3435 335);
DISPLAY 0.680851 (-3435 335);
PAINT MONO (-3435 335);
FORCEPROP 0 LASTPIN (-3425 375) $PN DH32
J 2
(-3435 385);
DISPLAY 0.680851 (-3435 385);
PAINT MONO (-3435 385);
FORCEPROP 0 LASTPIN (-3425 475) $PN DH38
J 2
(-3435 485);
DISPLAY 0.680851 (-3435 485);
PAINT MONO (-3435 485);
FORCEPROP 0 LASTPIN (-3425 -25) $PN DH4
J 2
(-3435 -15);
DISPLAY 0.680851 (-3435 -15);
PAINT MONO (-3435 -15);
FORCEPROP 0 LASTPIN (-3425 525) $PN DH40
J 2
(-3435 535);
DISPLAY 0.680851 (-3435 535);
PAINT MONO (-3435 535);
FORCEPROP 0 LASTPIN (-3425 625) $PN DH47
J 2
(-3435 635);
DISPLAY 0.680851 (-3435 635);
PAINT MONO (-3435 635);
FORCEPROP 0 LASTPIN (-3425 775) $PN DH57
J 2
(-3435 785);
DISPLAY 0.680851 (-3435 785);
PAINT MONO (-3435 785);
FORCEPROP 0 LASTPIN (-3425 925) $PN DH65
J 2
(-3435 935);
DISPLAY 0.680851 (-3435 935);
PAINT MONO (-3435 935);
FORCEPROP 0 LASTPIN (-3425 1025) $PN DH71
J 2
(-3435 1035);
DISPLAY 0.680851 (-3435 1035);
PAINT MONO (-3435 1035);
FORCEPROP 0 LASTPIN (-3425 1125) $PN DH77
J 2
(-3435 1135);
DISPLAY 0.680851 (-3435 1135);
PAINT MONO (-3435 1135);
FORCEPROP 0 LASTPIN (-3425 25) $PN DH8
J 2
(-3435 35);
DISPLAY 0.680851 (-3435 35);
PAINT MONO (-3435 35);
FORCEPROP 0 LASTPIN (-3425 1175) $PN DH85
J 2
(-3435 1185);
DISPLAY 0.680851 (-3435 1185);
PAINT MONO (-3435 1185);
FORCEPROP 0 LASTPIN (-3425 1225) $PN DJ19
J 2
(-3435 1235);
DISPLAY 0.680851 (-3435 1235);
PAINT MONO (-3435 1235);
FORCEPROP 0 LASTPIN (-3425 1275) $PN DJ23
J 2
(-3435 1285);
DISPLAY 0.680851 (-3435 1285);
PAINT MONO (-3435 1285);
FORCEPROP 0 LASTPIN (-3425 1375) $PN DJ29
J 2
(-3435 1385);
DISPLAY 0.680851 (-3435 1385);
PAINT MONO (-3435 1385);
FORCEPROP 0 LASTPIN (-3425 1425) $PN DJ31
J 2
(-3435 1435);
DISPLAY 0.680851 (-3435 1435);
PAINT MONO (-3435 1435);
FORCEPROP 0 LASTPIN (-3425 1525) $PN DJ37
J 2
(-3435 1535);
DISPLAY 0.680851 (-3435 1535);
PAINT MONO (-3435 1535);
FORCEPROP 0 LASTPIN (-3425 1575) $PN DJ41
J 2
(-3435 1585);
DISPLAY 0.680851 (-3435 1585);
PAINT MONO (-3435 1585);
FORCEPROP 0 LASTPIN (-3425 1625) $PN DJ43
J 2
(-3435 1635);
DISPLAY 0.680851 (-3435 1635);
PAINT MONO (-3435 1635);
FORCEPROP 0 LASTPIN (-3425 1675) $PN DJ48
J 2
(-3435 1685);
DISPLAY 0.680851 (-3435 1685);
PAINT MONO (-3435 1685);
FORCEPROP 0 LASTPIN (-3425 1725) $PN DJ50
J 2
(-3435 1735);
DISPLAY 0.680851 (-3435 1735);
PAINT MONO (-3435 1735);
FORCEPROP 0 LASTPIN (-3425 1825) $PN DJ56
J 2
(-3435 1835);
DISPLAY 0.680851 (-3435 1835);
PAINT MONO (-3435 1835);
FORCEPROP 0 LASTPIN (-3425 1875) $PN DJ60
J 2
(-3435 1885);
DISPLAY 0.680851 (-3435 1885);
PAINT MONO (-3435 1885);
FORCEPROP 0 LASTPIN (-3425 1975) $PN DJ66
J 2
(-3435 1985);
DISPLAY 0.680851 (-3435 1985);
PAINT MONO (-3435 1985);
FORCEPROP 0 LASTPIN (-3425 2075) $PN DJ72
J 2
(-3435 2085);
DISPLAY 0.680851 (-3435 2085);
PAINT MONO (-3435 2085);
FORCEPROP 0 LASTPIN (-3425 2125) $PN DJ74
J 2
(-3435 2135);
DISPLAY 0.680851 (-3435 2135);
PAINT MONO (-3435 2135);
FORCEPROP 0 LASTPIN (-3425 2175) $PN DJ80
J 2
(-3435 2185);
DISPLAY 0.680851 (-3435 2185);
PAINT MONO (-3435 2185);
FORCEPROP 0 LASTPIN (-3425 2225) $PN DJ82
J 2
(-3435 2235);
DISPLAY 0.680851 (-3435 2235);
PAINT MONO (-3435 2235);
FORCEPROP 0 LASTPIN (-3425 2275) $PN DJ84
J 2
(-3435 2285);
DISPLAY 0.680851 (-3435 2285);
PAINT MONO (-3435 2285);
FORCEPROP 0 LASTPIN (-3425 2325) $PN DJ88
J 2
(-3435 2335);
DISPLAY 0.680851 (-3435 2335);
PAINT MONO (-3435 2335);
FORCEPROP 0 LASTPIN (-3425 2525) $PN DK16
J 2
(-3435 2535);
DISPLAY 0.680851 (-3435 2535);
PAINT MONO (-3435 2535);
FORCEPROP 0 LASTPIN (-3425 2675) $PN DK30
J 2
(-3435 2685);
DISPLAY 0.680851 (-3435 2685);
PAINT MONO (-3435 2685);
FORCEPROP 0 LASTPIN (-3425 2725) $PN DK36
J 2
(-3435 2735);
DISPLAY 0.680851 (-3435 2735);
PAINT MONO (-3435 2735);
FORCEPROP 0 LASTPIN (-3425 2375) $PN DK4
J 2
(-3435 2385);
DISPLAY 0.680851 (-3435 2385);
PAINT MONO (-3435 2385);
FORCEPROP 0 LASTPIN (-3425 2825) $PN DK49
J 2
(-3435 2835);
DISPLAY 0.680851 (-3435 2835);
PAINT MONO (-3435 2835);
FORCEPROP 0 LASTPIN (-3425 3025) $PN DK73
J 2
(-3435 3035);
DISPLAY 0.680851 (-3435 3035);
PAINT MONO (-3435 3035);
FORCEPROP 0 LASTPIN (-3425 3075) $PN DK77
J 2
(-3435 3085);
DISPLAY 0.680851 (-3435 3085);
PAINT MONO (-3435 3085);
FORCEPROP 0 LASTPIN (-3425 3125) $PN DK79
J 2
(-3435 3135);
DISPLAY 0.680851 (-3435 3135);
PAINT MONO (-3435 3135);
FORCEPROP 0 LASTPIN (-3425 2425) $PN DK8
J 2
(-3435 2435);
DISPLAY 0.680851 (-3435 2435);
PAINT MONO (-3435 2435);
FORCEPROP 0 LASTPIN (-3425 3175) $PN DK81
J 2
(-3435 3185);
DISPLAY 0.680851 (-3435 3185);
PAINT MONO (-3435 3185);
FORCEPROP 0 LASTPIN (-3425 3225) $PN DK83
J 2
(-3435 3235);
DISPLAY 0.680851 (-3435 3235);
PAINT MONO (-3435 3235);
FORCEPROP 0 LASTPIN (-3425 3275) $PN DK87
J 2
(-3435 3285);
DISPLAY 0.680851 (-3435 3285);
PAINT MONO (-3435 3285);
FORCEPROP 0 LASTPIN (-3425 3325) $PN DK91
J 2
(-3435 3335);
DISPLAY 0.680851 (-3435 3335);
PAINT MONO (-3435 3335);
FORCEPROP 0 LASTPIN (-3425 3625) $PN DL39
J 2
(-3435 3635);
DISPLAY 0.680851 (-3435 3635);
PAINT MONO (-3435 3635);
FORCEPROP 0 LASTPIN (-3425 3725) $PN DL84
J 2
(-3435 3735);
DISPLAY 0.680851 (-3435 3735);
PAINT MONO (-3435 3735);
FORCEPROP 0 LASTPIN (-3425 3775) $PN DL88
J 2
(-3435 3785);
DISPLAY 0.680851 (-3435 3785);
PAINT MONO (-3435 3785);
FORCEPROP 0 LASTPIN (-3425 3475) $PN DL9
J 2
(-3435 3485);
DISPLAY 0.680851 (-3435 3485);
PAINT MONO (-3435 3485);
FORCEPROP 2 LAST CDS_LIB pure_quanta
J 0
(-2225 1800);
DISPLAY INVISIBLE (-2225 1800);
FORCEPROP 1 LAST NEEDS_NO_SIZE TRUE
J 0
(-2225 1800);
DISPLAY 0.723404 (-2225 1800);
PAINT GREEN (-2225 1800);
DISPLAY INVISIBLE (-2225 1800);
FORCEPROP 1 LAST CDS_LMAN_SYM_OUTLINE -1050,2150,1050,-2100
J 0
(-2225 1800);
DISPLAY 0.468085 (-2225 1800);
PAINT GREEN (-2225 1800);
DISPLAY INVISIBLE (-2225 1800);
FORCEPROP 2 LAST CDS_LOCATION U2
J 0
(-3275 4275);
DISPLAY 1.021277 (-3275 4275);
DISPLAY INVISIBLE (-3275 4275);
FORCEPROP 0 LAST $SEC 34
J 0
(-3275 4275);
DISPLAY 0.680851 (-3275 4275);
PAINT MONO (-3275 4275);
DISPLAY INVISIBLE (-3275 4275);
FORCEPROP 2 LAST CDS_SEC 34
J 0
(-3275 4275);
DISPLAY 1.021277 (-3275 4275);
DISPLAY INVISIBLE (-3275 4275);
FORCEPROP 1 LAST PATH I10
J 0
(-2225 1800);
DISPLAY 0.723404 (-2225 1800);
PAINT GREEN (-2225 1800);
DISPLAY INVISIBLE (-2225 1800);
FORCEADD SOCKET4677_AZIF0045P001C01CS..35
(825 1800);
FORCEPROP 1 LAST PART_NUMBER DGA^7000023
J 0
(-225 4050);
DISPLAY 0.723404 (-225 4050);
PAINT GREEN (-225 4050);
DISPLAY INVISIBLE (-225 4050);
FORCEPROP 2 LAST PART_TYPE SMLF
J 0
(-225 4225);
DISPLAY 1.021277 (-225 4225);
FORCEPROP 1 LAST MATERIAL IO
J 0
(-225 3975);
DISPLAY 0.723404 (-225 3975);
PAINT GREEN (-225 3975);
FORCEPROP 2 LAST VALUE SOCKET4677_AZIF0045-P001C01CS
J 0
(-225 4175);
DISPLAY 1.021277 (-225 4175);
FORCEPROP 1 LAST $LOCATION U2
J 0
(-225 4125);
DISPLAY 0.723404 (-225 4125);
PAINT GREEN (-225 4125);
FORCEPROP 0 LASTPIN (2025 625) $PN CM16
J 0
(2035 635);
DISPLAY 0.680851 (2035 635);
PAINT MONO (2035 635);
FORCEPROP 0 LASTPIN (2025 725) $PN CM22
J 0
(2035 735);
DISPLAY 0.680851 (2035 735);
PAINT MONO (2035 735);
FORCEPROP 0 LASTPIN (2025 1375) $PN CN76
J 0
(2035 1385);
DISPLAY 0.680851 (2035 1385);
PAINT MONO (2035 1385);
FORCEPROP 0 LASTPIN (2025 1675) $PN CP16
J 0
(2035 1685);
DISPLAY 0.680851 (2035 1685);
PAINT MONO (2035 1685);
FORCEPROP 0 LASTPIN (2025 1875) $PN CP79
J 0
(2035 1885);
DISPLAY 0.680851 (2035 1885);
PAINT MONO (2035 1885);
FORCEPROP 0 LASTPIN (2025 2475) $PN CR78
J 0
(2035 2485);
DISPLAY 0.680851 (2035 2485);
PAINT MONO (2035 2485);
FORCEPROP 0 LASTPIN (2025 2875) $PN CT16
J 0
(2035 2885);
DISPLAY 0.680851 (2035 2885);
PAINT MONO (2035 2885);
FORCEPROP 0 LASTPIN (2025 2675) $PN CT4
J 0
(2035 2685);
DISPLAY 0.680851 (2035 2685);
PAINT MONO (2035 2685);
FORCEPROP 0 LASTPIN (2025 2725) $PN CT8
J 0
(2035 2735);
DISPLAY 0.680851 (2035 2735);
PAINT MONO (2035 2735);
FORCEPROP 0 LASTPIN (2025 3075) $PN CT89
J 0
(2035 3085);
DISPLAY 0.680851 (2035 3085);
PAINT MONO (2035 3085);
FORCEPROP 0 LASTPIN (2025 3275) $PN CU25
J 0
(2035 3285);
DISPLAY 0.680851 (2035 3285);
PAINT MONO (2035 3285);
FORCEPROP 0 LASTPIN (2025 3475) $PN CU72
J 0
(2035 3485);
DISPLAY 0.680851 (2035 3485);
PAINT MONO (2035 3485);
FORCEPROP 0 LASTPIN (2025 3525) $PN CU78
J 0
(2035 3535);
DISPLAY 0.680851 (2035 3535);
PAINT MONO (2035 3535);
FORCEPROP 0 LASTPIN (-375 -175) $PN CV16
J 2
(-385 -165);
DISPLAY 0.680851 (-385 -165);
PAINT MONO (-385 -165);
FORCEPROP 0 LASTPIN (-375 -125) $PN CV26
J 2
(-385 -115);
DISPLAY 0.680851 (-385 -115);
PAINT MONO (-385 -115);
FORCEPROP 0 LASTPIN (-375 -25) $PN CV79
J 2
(-385 -15);
DISPLAY 0.680851 (-385 -15);
PAINT MONO (-385 -15);
FORCEPROP 0 LASTPIN (-375 425) $PN CW33
J 2
(-385 435);
DISPLAY 0.680851 (-385 435);
PAINT MONO (-385 435);
FORCEPROP 0 LASTPIN (-375 475) $PN CW70
J 2
(-385 485);
DISPLAY 0.680851 (-385 485);
PAINT MONO (-385 485);
FORCEPROP 0 LASTPIN (-375 725) $PN CY4
J 2
(-385 735);
DISPLAY 0.680851 (-385 735);
PAINT MONO (-385 735);
FORCEPROP 0 LASTPIN (-375 1775) $PN DA43
J 2
(-385 1785);
DISPLAY 0.680851 (-385 1785);
PAINT MONO (-385 1785);
FORCEPROP 0 LASTPIN (-375 2225) $PN DA68
J 2
(-385 2235);
DISPLAY 0.680851 (-385 2235);
PAINT MONO (-385 2235);
FORCEPROP 0 LASTPIN (-375 2725) $PN DB16
J 2
(-385 2735);
DISPLAY 0.680851 (-385 2735);
PAINT MONO (-385 2735);
FORCEPROP 0 LASTPIN (-375 2775) $PN DB20
J 2
(-385 2785);
DISPLAY 0.680851 (-385 2785);
PAINT MONO (-385 2785);
FORCEPROP 0 LASTPIN (-375 2875) $PN DB26
J 2
(-385 2885);
DISPLAY 0.680851 (-385 2885);
PAINT MONO (-385 2885);
FORCEPROP 0 LASTPIN (-375 3025) $PN DB34
J 2
(-385 3035);
DISPLAY 0.680851 (-385 3035);
PAINT MONO (-385 3035);
FORCEPROP 0 LASTPIN (-375 3175) $PN DB44
J 2
(-385 3185);
DISPLAY 0.680851 (-385 3185);
PAINT MONO (-385 3185);
FORCEPROP 0 LASTPIN (-375 3275) $PN DB51
J 2
(-385 3285);
DISPLAY 0.680851 (-385 3285);
PAINT MONO (-385 3285);
FORCEPROP 0 LASTPIN (-375 3325) $PN DB53
J 2
(-385 3335);
DISPLAY 0.680851 (-385 3335);
PAINT MONO (-385 3335);
FORCEPROP 0 LASTPIN (-375 3425) $PN DB59
J 2
(-385 3435);
DISPLAY 0.680851 (-385 3435);
PAINT MONO (-385 3435);
FORCEPROP 0 LASTPIN (-375 3475) $PN DB63
J 2
(-385 3485);
DISPLAY 0.680851 (-385 3485);
PAINT MONO (-385 3485);
FORCEPROP 0 LASTPIN (-375 3575) $PN DB69
J 2
(-385 3585);
DISPLAY 0.680851 (-385 3585);
PAINT MONO (-385 3585);
FORCEPROP 0 LASTPIN (-375 3675) $PN DB75
J 2
(-385 3685);
DISPLAY 0.680851 (-385 3685);
PAINT MONO (-385 3685);
FORCEPROP 0 LASTPIN (2025 -175) $PN CK63
J 0
(2035 -165);
DISPLAY 0.680851 (2035 -165);
PAINT MONO (2035 -165);
FORCEPROP 0 LASTPIN (2025 -125) $PN CK69
J 0
(2035 -115);
DISPLAY 0.680851 (2035 -115);
PAINT MONO (2035 -115);
FORCEPROP 0 LASTPIN (2025 -75) $PN CK81
J 0
(2035 -65);
DISPLAY 0.680851 (2035 -65);
PAINT MONO (2035 -65);
FORCEPROP 0 LASTPIN (2025 -25) $PN CL1
J 0
(2035 -15);
DISPLAY 0.680851 (2035 -15);
PAINT MONO (2035 -15);
FORCEPROP 0 LASTPIN (2025 125) $PN CL13
J 0
(2035 135);
DISPLAY 0.680851 (2035 135);
PAINT MONO (2035 135);
FORCEPROP 0 LASTPIN (2025 175) $PN CL17
J 0
(2035 185);
DISPLAY 0.680851 (2035 185);
PAINT MONO (2035 185);
FORCEPROP 0 LASTPIN (2025 25) $PN CL5
J 0
(2035 35);
DISPLAY 0.680851 (2035 35);
PAINT MONO (2035 35);
FORCEPROP 0 LASTPIN (2025 225) $PN CL62
J 0
(2035 235);
DISPLAY 0.680851 (2035 235);
PAINT MONO (2035 235);
FORCEPROP 0 LASTPIN (2025 275) $PN CL74
J 0
(2035 285);
DISPLAY 0.680851 (2035 285);
PAINT MONO (2035 285);
FORCEPROP 0 LASTPIN (2025 325) $PN CL78
J 0
(2035 335);
DISPLAY 0.680851 (2035 335);
PAINT MONO (2035 335);
FORCEPROP 0 LASTPIN (2025 375) $PN CL80
J 0
(2035 385);
DISPLAY 0.680851 (2035 385);
PAINT MONO (2035 385);
FORCEPROP 0 LASTPIN (2025 425) $PN CL82
J 0
(2035 435);
DISPLAY 0.680851 (2035 435);
PAINT MONO (2035 435);
FORCEPROP 0 LASTPIN (2025 75) $PN CL9
J 0
(2035 85);
DISPLAY 0.680851 (2035 85);
PAINT MONO (2035 85);
FORCEPROP 0 LASTPIN (2025 575) $PN CM12
J 0
(2035 585);
DISPLAY 0.680851 (2035 585);
PAINT MONO (2035 585);
FORCEPROP 0 LASTPIN (2025 675) $PN CM20
J 0
(2035 685);
DISPLAY 0.680851 (2035 685);
PAINT MONO (2035 685);
FORCEPROP 0 LASTPIN (2025 775) $PN CM24
J 0
(2035 785);
DISPLAY 0.680851 (2035 785);
PAINT MONO (2035 785);
FORCEPROP 0 LASTPIN (2025 475) $PN CM4
J 0
(2035 485);
DISPLAY 0.680851 (2035 485);
PAINT MONO (2035 485);
FORCEPROP 0 LASTPIN (2025 825) $PN CM61
J 0
(2035 835);
DISPLAY 0.680851 (2035 835);
PAINT MONO (2035 835);
FORCEPROP 0 LASTPIN (2025 875) $PN CM65
J 0
(2035 885);
DISPLAY 0.680851 (2035 885);
PAINT MONO (2035 885);
FORCEPROP 0 LASTPIN (2025 925) $PN CM67
J 0
(2035 935);
DISPLAY 0.680851 (2035 935);
PAINT MONO (2035 935);
FORCEPROP 0 LASTPIN (2025 975) $PN CM79
J 0
(2035 985);
DISPLAY 0.680851 (2035 985);
PAINT MONO (2035 985);
FORCEPROP 0 LASTPIN (2025 525) $PN CM8
J 0
(2035 535);
DISPLAY 0.680851 (2035 535);
PAINT MONO (2035 535);
FORCEPROP 0 LASTPIN (2025 1025) $PN CM81
J 0
(2035 1035);
DISPLAY 0.680851 (2035 1035);
PAINT MONO (2035 1035);
FORCEPROP 0 LASTPIN (2025 1075) $PN CM83
J 0
(2035 1085);
DISPLAY 0.680851 (2035 1085);
PAINT MONO (2035 1085);
FORCEPROP 0 LASTPIN (2025 1125) $PN CM85
J 0
(2035 1135);
DISPLAY 0.680851 (2035 1135);
PAINT MONO (2035 1135);
FORCEPROP 0 LASTPIN (2025 1175) $PN CN68
J 0
(2035 1185);
DISPLAY 0.680851 (2035 1185);
PAINT MONO (2035 1185);
FORCEPROP 0 LASTPIN (2025 1225) $PN CN70
J 0
(2035 1235);
DISPLAY 0.680851 (2035 1235);
PAINT MONO (2035 1235);
FORCEPROP 0 LASTPIN (2025 1275) $PN CN72
J 0
(2035 1285);
DISPLAY 0.680851 (2035 1285);
PAINT MONO (2035 1285);
FORCEPROP 0 LASTPIN (2025 1325) $PN CN74
J 0
(2035 1335);
DISPLAY 0.680851 (2035 1335);
PAINT MONO (2035 1335);
FORCEPROP 0 LASTPIN (2025 1425) $PN CN84
J 0
(2035 1435);
DISPLAY 0.680851 (2035 1435);
PAINT MONO (2035 1435);
FORCEPROP 0 LASTPIN (2025 1475) $PN CN86
J 0
(2035 1485);
DISPLAY 0.680851 (2035 1485);
PAINT MONO (2035 1485);
FORCEPROP 0 LASTPIN (2025 1625) $PN CP12
J 0
(2035 1635);
DISPLAY 0.680851 (2035 1635);
PAINT MONO (2035 1635);
FORCEPROP 0 LASTPIN (2025 1725) $PN CP18
J 0
(2035 1735);
DISPLAY 0.680851 (2035 1735);
PAINT MONO (2035 1735);
FORCEPROP 0 LASTPIN (2025 1525) $PN CP4
J 0
(2035 1535);
DISPLAY 0.680851 (2035 1535);
PAINT MONO (2035 1535);
FORCEPROP 0 LASTPIN (2025 1775) $PN CP75
J 0
(2035 1785);
DISPLAY 0.680851 (2035 1785);
PAINT MONO (2035 1785);
FORCEPROP 0 LASTPIN (2025 1825) $PN CP77
J 0
(2035 1835);
DISPLAY 0.680851 (2035 1835);
PAINT MONO (2035 1835);
FORCEPROP 0 LASTPIN (2025 1575) $PN CP8
J 0
(2035 1585);
DISPLAY 0.680851 (2035 1585);
PAINT MONO (2035 1585);
FORCEPROP 0 LASTPIN (2025 1925) $PN CP83
J 0
(2035 1935);
DISPLAY 0.680851 (2035 1935);
PAINT MONO (2035 1935);
FORCEPROP 0 LASTPIN (2025 1975) $PN CP87
J 0
(2035 1985);
DISPLAY 0.680851 (2035 1985);
PAINT MONO (2035 1985);
FORCEPROP 0 LASTPIN (2025 2025) $PN CP91
J 0
(2035 2035);
DISPLAY 0.680851 (2035 2035);
PAINT MONO (2035 2035);
FORCEPROP 0 LASTPIN (2025 2075) $PN CR1
J 0
(2035 2085);
DISPLAY 0.680851 (2035 2085);
PAINT MONO (2035 2085);
FORCEPROP 0 LASTPIN (2025 2225) $PN CR11
J 0
(2035 2235);
DISPLAY 0.680851 (2035 2235);
PAINT MONO (2035 2235);
FORCEPROP 0 LASTPIN (2025 2275) $PN CR13
J 0
(2035 2285);
DISPLAY 0.680851 (2035 2285);
PAINT MONO (2035 2285);
FORCEPROP 0 LASTPIN (2025 2325) $PN CR17
J 0
(2035 2335);
DISPLAY 0.680851 (2035 2335);
PAINT MONO (2035 2335);
FORCEPROP 0 LASTPIN (2025 2125) $PN CR5
J 0
(2035 2135);
DISPLAY 0.680851 (2035 2135);
PAINT MONO (2035 2135);
FORCEPROP 0 LASTPIN (2025 2375) $PN CR62
J 0
(2035 2385);
DISPLAY 0.680851 (2035 2385);
PAINT MONO (2035 2385);
FORCEPROP 0 LASTPIN (2025 2425) $PN CR64
J 0
(2035 2435);
DISPLAY 0.680851 (2035 2435);
PAINT MONO (2035 2435);
FORCEPROP 0 LASTPIN (2025 2525) $PN CR84
J 0
(2035 2535);
DISPLAY 0.680851 (2035 2535);
PAINT MONO (2035 2535);
FORCEPROP 0 LASTPIN (2025 2575) $PN CR88
J 0
(2035 2585);
DISPLAY 0.680851 (2035 2585);
PAINT MONO (2035 2585);
FORCEPROP 0 LASTPIN (2025 2175) $PN CR9
J 0
(2035 2185);
DISPLAY 0.680851 (2035 2185);
PAINT MONO (2035 2185);
FORCEPROP 0 LASTPIN (2025 2625) $PN CR90
J 0
(2035 2635);
DISPLAY 0.680851 (2035 2635);
PAINT MONO (2035 2635);
FORCEPROP 0 LASTPIN (2025 2775) $PN CT10
J 0
(2035 2785);
DISPLAY 0.680851 (2035 2785);
PAINT MONO (2035 2785);
FORCEPROP 0 LASTPIN (2025 2825) $PN CT12
J 0
(2035 2835);
DISPLAY 0.680851 (2035 2835);
PAINT MONO (2035 2835);
FORCEPROP 0 LASTPIN (2025 2925) $PN CT69
J 0
(2035 2935);
DISPLAY 0.680851 (2035 2935);
PAINT MONO (2035 2935);
FORCEPROP 0 LASTPIN (2025 2975) $PN CT73
J 0
(2035 2985);
DISPLAY 0.680851 (2035 2985);
PAINT MONO (2035 2985);
FORCEPROP 0 LASTPIN (2025 3025) $PN CT81
J 0
(2035 3035);
DISPLAY 0.680851 (2035 3035);
PAINT MONO (2035 3035);
FORCEPROP 0 LASTPIN (2025 3125) $PN CU19
J 0
(2035 3135);
DISPLAY 0.680851 (2035 3135);
PAINT MONO (2035 3135);
FORCEPROP 0 LASTPIN (2025 3175) $PN CU21
J 0
(2035 3185);
DISPLAY 0.680851 (2035 3185);
PAINT MONO (2035 3185);
FORCEPROP 0 LASTPIN (2025 3225) $PN CU23
J 0
(2035 3235);
DISPLAY 0.680851 (2035 3235);
PAINT MONO (2035 3235);
FORCEPROP 0 LASTPIN (2025 3325) $PN CU60
J 0
(2035 3335);
DISPLAY 0.680851 (2035 3335);
PAINT MONO (2035 3335);
FORCEPROP 0 LASTPIN (2025 3375) $PN CU66
J 0
(2035 3385);
DISPLAY 0.680851 (2035 3385);
PAINT MONO (2035 3385);
FORCEPROP 0 LASTPIN (2025 3425) $PN CU68
J 0
(2035 3435);
DISPLAY 0.680851 (2035 3435);
PAINT MONO (2035 3435);
FORCEPROP 0 LASTPIN (2025 3575) $PN CU84
J 0
(2035 3585);
DISPLAY 0.680851 (2035 3585);
PAINT MONO (2035 3585);
FORCEPROP 0 LASTPIN (2025 3625) $PN CU88
J 0
(2035 3635);
DISPLAY 0.680851 (2035 3635);
PAINT MONO (2035 3635);
FORCEPROP 0 LASTPIN (2025 3775) $PN CV12
J 0
(2035 3785);
DISPLAY 0.680851 (2035 3785);
PAINT MONO (2035 3785);
FORCEPROP 0 LASTPIN (2025 3675) $PN CV4
J 0
(2035 3685);
DISPLAY 0.680851 (2035 3685);
PAINT MONO (2035 3685);
FORCEPROP 0 LASTPIN (-375 -75) $PN CV75
J 2
(-385 -65);
DISPLAY 0.680851 (-385 -65);
PAINT MONO (-385 -65);
FORCEPROP 0 LASTPIN (2025 3725) $PN CV8
J 0
(2035 3735);
DISPLAY 0.680851 (2035 3735);
PAINT MONO (2035 3735);
FORCEPROP 0 LASTPIN (-375 25) $PN CV83
J 2
(-385 35);
DISPLAY 0.680851 (-385 35);
PAINT MONO (-385 35);
FORCEPROP 0 LASTPIN (-375 75) $PN CV87
J 2
(-385 85);
DISPLAY 0.680851 (-385 85);
PAINT MONO (-385 85);
FORCEPROP 0 LASTPIN (-375 125) $PN CV91
J 2
(-385 135);
DISPLAY 0.680851 (-385 135);
PAINT MONO (-385 135);
FORCEPROP 0 LASTPIN (-375 175) $PN CW1
J 2
(-385 185);
DISPLAY 0.680851 (-385 185);
PAINT MONO (-385 185);
FORCEPROP 0 LASTPIN (-375 325) $PN CW13
J 2
(-385 335);
DISPLAY 0.680851 (-385 335);
PAINT MONO (-385 335);
FORCEPROP 0 LASTPIN (-375 375) $PN CW17
J 2
(-385 385);
DISPLAY 0.680851 (-385 385);
PAINT MONO (-385 385);
FORCEPROP 0 LASTPIN (-375 225) $PN CW5
J 2
(-385 235);
DISPLAY 0.680851 (-385 235);
PAINT MONO (-385 235);
FORCEPROP 0 LASTPIN (-375 525) $PN CW72
J 2
(-385 535);
DISPLAY 0.680851 (-385 535);
PAINT MONO (-385 535);
FORCEPROP 0 LASTPIN (-375 575) $PN CW78
J 2
(-385 585);
DISPLAY 0.680851 (-385 585);
PAINT MONO (-385 585);
FORCEPROP 0 LASTPIN (-375 625) $PN CW84
J 2
(-385 635);
DISPLAY 0.680851 (-385 635);
PAINT MONO (-385 635);
FORCEPROP 0 LASTPIN (-375 675) $PN CW88
J 2
(-385 685);
DISPLAY 0.680851 (-385 685);
PAINT MONO (-385 685);
FORCEPROP 0 LASTPIN (-375 275) $PN CW9
J 2
(-385 285);
DISPLAY 0.680851 (-385 285);
PAINT MONO (-385 285);
FORCEPROP 0 LASTPIN (-375 825) $PN CY12
J 2
(-385 835);
DISPLAY 0.680851 (-385 835);
PAINT MONO (-385 835);
FORCEPROP 0 LASTPIN (-375 875) $PN CY16
J 2
(-385 885);
DISPLAY 0.680851 (-385 885);
PAINT MONO (-385 885);
FORCEPROP 0 LASTPIN (-375 925) $PN CY18
J 2
(-385 935);
DISPLAY 0.680851 (-385 935);
PAINT MONO (-385 935);
FORCEPROP 0 LASTPIN (-375 975) $PN CY26
J 2
(-385 985);
DISPLAY 0.680851 (-385 985);
PAINT MONO (-385 985);
FORCEPROP 0 LASTPIN (-375 1025) $PN CY30
J 2
(-385 1035);
DISPLAY 0.680851 (-385 1035);
PAINT MONO (-385 1035);
FORCEPROP 0 LASTPIN (-375 1075) $PN CY63
J 2
(-385 1085);
DISPLAY 0.680851 (-385 1085);
PAINT MONO (-385 1085);
FORCEPROP 0 LASTPIN (-375 1125) $PN CY73
J 2
(-385 1135);
DISPLAY 0.680851 (-385 1135);
PAINT MONO (-385 1135);
FORCEPROP 0 LASTPIN (-375 1175) $PN CY77
J 2
(-385 1185);
DISPLAY 0.680851 (-385 1185);
PAINT MONO (-385 1185);
FORCEPROP 0 LASTPIN (-375 775) $PN CY8
J 2
(-385 785);
DISPLAY 0.680851 (-385 785);
PAINT MONO (-385 785);
FORCEPROP 0 LASTPIN (-375 1225) $PN CY81
J 2
(-385 1235);
DISPLAY 0.680851 (-385 1235);
PAINT MONO (-385 1235);
FORCEPROP 0 LASTPIN (-375 1275) $PN CY83
J 2
(-385 1285);
DISPLAY 0.680851 (-385 1285);
PAINT MONO (-385 1285);
FORCEPROP 0 LASTPIN (-375 1325) $PN DA19
J 2
(-385 1335);
DISPLAY 0.680851 (-385 1335);
PAINT MONO (-385 1335);
FORCEPROP 0 LASTPIN (-375 1375) $PN DA23
J 2
(-385 1385);
DISPLAY 0.680851 (-385 1385);
PAINT MONO (-385 1385);
FORCEPROP 0 LASTPIN (-375 1425) $PN DA25
J 2
(-385 1435);
DISPLAY 0.680851 (-385 1435);
PAINT MONO (-385 1435);
FORCEPROP 0 LASTPIN (-375 1475) $PN DA29
J 2
(-385 1485);
DISPLAY 0.680851 (-385 1485);
PAINT MONO (-385 1485);
FORCEPROP 0 LASTPIN (-375 1525) $PN DA31
J 2
(-385 1535);
DISPLAY 0.680851 (-385 1535);
PAINT MONO (-385 1535);
FORCEPROP 0 LASTPIN (-375 1575) $PN DA33
J 2
(-385 1585);
DISPLAY 0.680851 (-385 1585);
PAINT MONO (-385 1585);
FORCEPROP 0 LASTPIN (-375 1625) $PN DA35
J 2
(-385 1635);
DISPLAY 0.680851 (-385 1635);
PAINT MONO (-385 1635);
FORCEPROP 0 LASTPIN (-375 1675) $PN DA37
J 2
(-385 1685);
DISPLAY 0.680851 (-385 1685);
PAINT MONO (-385 1685);
FORCEPROP 0 LASTPIN (-375 1725) $PN DA41
J 2
(-385 1735);
DISPLAY 0.680851 (-385 1735);
PAINT MONO (-385 1735);
FORCEPROP 0 LASTPIN (-375 1825) $PN DA48
J 2
(-385 1835);
DISPLAY 0.680851 (-385 1835);
PAINT MONO (-385 1835);
FORCEPROP 0 LASTPIN (-375 1875) $PN DA50
J 2
(-385 1885);
DISPLAY 0.680851 (-385 1885);
PAINT MONO (-385 1885);
FORCEPROP 0 LASTPIN (-375 1925) $PN DA54
J 2
(-385 1935);
DISPLAY 0.680851 (-385 1935);
PAINT MONO (-385 1935);
FORCEPROP 0 LASTPIN (-375 1975) $PN DA56
J 2
(-385 1985);
DISPLAY 0.680851 (-385 1985);
PAINT MONO (-385 1985);
FORCEPROP 0 LASTPIN (-375 2025) $PN DA58
J 2
(-385 2035);
DISPLAY 0.680851 (-385 2035);
PAINT MONO (-385 2035);
FORCEPROP 0 LASTPIN (-375 2075) $PN DA60
J 2
(-385 2085);
DISPLAY 0.680851 (-385 2085);
PAINT MONO (-385 2085);
FORCEPROP 0 LASTPIN (-375 2125) $PN DA62
J 2
(-385 2135);
DISPLAY 0.680851 (-385 2135);
PAINT MONO (-385 2135);
FORCEPROP 0 LASTPIN (-375 2175) $PN DA66
J 2
(-385 2185);
DISPLAY 0.680851 (-385 2185);
PAINT MONO (-385 2185);
FORCEPROP 0 LASTPIN (-375 2275) $PN DA72
J 2
(-385 2285);
DISPLAY 0.680851 (-385 2285);
PAINT MONO (-385 2285);
FORCEPROP 0 LASTPIN (-375 2325) $PN DA74
J 2
(-385 2335);
DISPLAY 0.680851 (-385 2335);
PAINT MONO (-385 2335);
FORCEPROP 0 LASTPIN (-375 2375) $PN DA80
J 2
(-385 2385);
DISPLAY 0.680851 (-385 2385);
PAINT MONO (-385 2385);
FORCEPROP 0 LASTPIN (-375 2425) $PN DA82
J 2
(-385 2435);
DISPLAY 0.680851 (-385 2435);
PAINT MONO (-385 2435);
FORCEPROP 0 LASTPIN (-375 2475) $PN DA84
J 2
(-385 2485);
DISPLAY 0.680851 (-385 2485);
PAINT MONO (-385 2485);
FORCEPROP 0 LASTPIN (-375 2525) $PN DA88
J 2
(-385 2535);
DISPLAY 0.680851 (-385 2535);
PAINT MONO (-385 2535);
FORCEPROP 0 LASTPIN (-375 2675) $PN DB12
J 2
(-385 2685);
DISPLAY 0.680851 (-385 2685);
PAINT MONO (-385 2685);
FORCEPROP 0 LASTPIN (-375 2825) $PN DB22
J 2
(-385 2835);
DISPLAY 0.680851 (-385 2835);
PAINT MONO (-385 2835);
FORCEPROP 0 LASTPIN (-375 2925) $PN DB28
J 2
(-385 2935);
DISPLAY 0.680851 (-385 2935);
PAINT MONO (-385 2935);
FORCEPROP 0 LASTPIN (-375 2975) $PN DB32
J 2
(-385 2985);
DISPLAY 0.680851 (-385 2985);
PAINT MONO (-385 2985);
FORCEPROP 0 LASTPIN (-375 3075) $PN DB38
J 2
(-385 3085);
DISPLAY 0.680851 (-385 3085);
PAINT MONO (-385 3085);
FORCEPROP 0 LASTPIN (-375 2575) $PN DB4
J 2
(-385 2585);
DISPLAY 0.680851 (-385 2585);
PAINT MONO (-385 2585);
FORCEPROP 0 LASTPIN (-375 3125) $PN DB40
J 2
(-385 3135);
DISPLAY 0.680851 (-385 3135);
PAINT MONO (-385 3135);
FORCEPROP 0 LASTPIN (-375 3225) $PN DB47
J 2
(-385 3235);
DISPLAY 0.680851 (-385 3235);
PAINT MONO (-385 3235);
FORCEPROP 0 LASTPIN (-375 3375) $PN DB57
J 2
(-385 3385);
DISPLAY 0.680851 (-385 3385);
PAINT MONO (-385 3385);
FORCEPROP 0 LASTPIN (-375 3525) $PN DB65
J 2
(-385 3535);
DISPLAY 0.680851 (-385 3535);
PAINT MONO (-385 3535);
FORCEPROP 0 LASTPIN (-375 3625) $PN DB71
J 2
(-385 3635);
DISPLAY 0.680851 (-385 3635);
PAINT MONO (-385 3635);
FORCEPROP 0 LASTPIN (-375 3725) $PN DB77
J 2
(-385 3735);
DISPLAY 0.680851 (-385 3735);
PAINT MONO (-385 3735);
FORCEPROP 0 LASTPIN (-375 2625) $PN DB8
J 2
(-385 2635);
DISPLAY 0.680851 (-385 2635);
PAINT MONO (-385 2635);
FORCEPROP 0 LASTPIN (-375 3775) $PN DB87
J 2
(-385 3785);
DISPLAY 0.680851 (-385 3785);
PAINT MONO (-385 3785);
FORCEPROP 2 LAST CDS_LIB pure_quanta
J 0
(825 1800);
DISPLAY INVISIBLE (825 1800);
FORCEPROP 1 LAST NEEDS_NO_SIZE TRUE
J 0
(825 1800);
DISPLAY 0.723404 (825 1800);
PAINT GREEN (825 1800);
DISPLAY INVISIBLE (825 1800);
FORCEPROP 1 LAST CDS_LMAN_SYM_OUTLINE -1050,2150,1050,-2100
J 0
(825 1800);
DISPLAY 0.468085 (825 1800);
PAINT GREEN (825 1800);
DISPLAY INVISIBLE (825 1800);
FORCEPROP 2 LAST CDS_LOCATION U2
J 0
(-225 4275);
DISPLAY 1.021277 (-225 4275);
DISPLAY INVISIBLE (-225 4275);
FORCEPROP 0 LAST $SEC 35
J 0
(-225 4275);
DISPLAY 0.680851 (-225 4275);
PAINT MONO (-225 4275);
DISPLAY INVISIBLE (-225 4275);
FORCEPROP 2 LAST CDS_SEC 35
J 0
(-225 4275);
DISPLAY 1.021277 (-225 4275);
DISPLAY INVISIBLE (-225 4275);
FORCEPROP 1 LAST PATH I11
J 0
(825 1800);
DISPLAY 0.723404 (825 1800);
PAINT GREEN (825 1800);
DISPLAY INVISIBLE (825 1800);
FORCEADD SOCKET4677_AZIF0045P001C01CS..36
(3850 1800);
FORCEPROP 1 LAST PART_NUMBER DGA^7000023
J 0
(2800 4050);
DISPLAY 0.723404 (2800 4050);
PAINT GREEN (2800 4050);
DISPLAY INVISIBLE (2800 4050);
FORCEPROP 2 LAST PART_TYPE SMLF
J 0
(2800 4225);
DISPLAY 1.021277 (2800 4225);
FORCEPROP 1 LAST MATERIAL IO
J 0
(2800 3975);
DISPLAY 0.723404 (2800 3975);
PAINT GREEN (2800 3975);
FORCEPROP 2 LAST VALUE SOCKET4677_AZIF0045-P001C01CS
J 0
(2800 4175);
DISPLAY 1.021277 (2800 4175);
FORCEPROP 1 LAST $LOCATION U2
J 0
(2800 4125);
DISPLAY 0.723404 (2800 4125);
PAINT GREEN (2800 4125);
FORCEPROP 0 LASTPIN (2650 3425) $PN CJ76
J 2
(2640 3435);
DISPLAY 0.680851 (2640 3435);
PAINT MONO (2640 3435);
FORCEPROP 0 LASTPIN (2650 3525) $PN CK4
J 2
(2640 3535);
DISPLAY 0.680851 (2640 3535);
PAINT MONO (2640 3535);
FORCEPROP 0 LASTPIN (5050 -175) $PN BR35
J 0
(5060 -165);
DISPLAY 0.680851 (5060 -165);
PAINT MONO (5060 -165);
FORCEPROP 0 LASTPIN (5050 -125) $PN BR37
J 0
(5060 -115);
DISPLAY 0.680851 (5060 -115);
PAINT MONO (5060 -115);
FORCEPROP 0 LASTPIN (5050 -75) $PN BR39
J 0
(5060 -65);
DISPLAY 0.680851 (5060 -65);
PAINT MONO (5060 -65);
FORCEPROP 0 LASTPIN (5050 -25) $PN BR41
J 0
(5060 -15);
DISPLAY 0.680851 (5060 -15);
PAINT MONO (5060 -15);
FORCEPROP 0 LASTPIN (5050 25) $PN BR43
J 0
(5060 35);
DISPLAY 0.680851 (5060 35);
PAINT MONO (5060 35);
FORCEPROP 0 LASTPIN (5050 75) $PN BR45
J 0
(5060 85);
DISPLAY 0.680851 (5060 85);
PAINT MONO (5060 85);
FORCEPROP 0 LASTPIN (5050 125) $PN BR48
J 0
(5060 135);
DISPLAY 0.680851 (5060 135);
PAINT MONO (5060 135);
FORCEPROP 0 LASTPIN (5050 175) $PN BR50
J 0
(5060 185);
DISPLAY 0.680851 (5060 185);
PAINT MONO (5060 185);
FORCEPROP 0 LASTPIN (5050 225) $PN BR52
J 0
(5060 235);
DISPLAY 0.680851 (5060 235);
PAINT MONO (5060 235);
FORCEPROP 0 LASTPIN (5050 275) $PN BR54
J 0
(5060 285);
DISPLAY 0.680851 (5060 285);
PAINT MONO (5060 285);
FORCEPROP 0 LASTPIN (5050 325) $PN BR56
J 0
(5060 335);
DISPLAY 0.680851 (5060 335);
PAINT MONO (5060 335);
FORCEPROP 0 LASTPIN (5050 375) $PN BR58
J 0
(5060 385);
DISPLAY 0.680851 (5060 385);
PAINT MONO (5060 385);
FORCEPROP 0 LASTPIN (5050 425) $PN BR64
J 0
(5060 435);
DISPLAY 0.680851 (5060 435);
PAINT MONO (5060 435);
FORCEPROP 0 LASTPIN (5050 475) $PN BR66
J 0
(5060 485);
DISPLAY 0.680851 (5060 485);
PAINT MONO (5060 485);
FORCEPROP 0 LASTPIN (5050 525) $PN BR68
J 0
(5060 535);
DISPLAY 0.680851 (5060 535);
PAINT MONO (5060 535);
FORCEPROP 0 LASTPIN (5050 575) $PN BR70
J 0
(5060 585);
DISPLAY 0.680851 (5060 585);
PAINT MONO (5060 585);
FORCEPROP 0 LASTPIN (5050 625) $PN BR72
J 0
(5060 635);
DISPLAY 0.680851 (5060 635);
PAINT MONO (5060 635);
FORCEPROP 0 LASTPIN (5050 675) $PN BR74
J 0
(5060 685);
DISPLAY 0.680851 (5060 685);
PAINT MONO (5060 685);
FORCEPROP 0 LASTPIN (5050 725) $PN BR76
J 0
(5060 735);
DISPLAY 0.680851 (5060 735);
PAINT MONO (5060 735);
FORCEPROP 0 LASTPIN (5050 775) $PN BR80
J 0
(5060 785);
DISPLAY 0.680851 (5060 785);
PAINT MONO (5060 785);
FORCEPROP 0 LASTPIN (5050 825) $PN BR82
J 0
(5060 835);
DISPLAY 0.680851 (5060 835);
PAINT MONO (5060 835);
FORCEPROP 0 LASTPIN (5050 875) $PN BR84
J 0
(5060 885);
DISPLAY 0.680851 (5060 885);
PAINT MONO (5060 885);
FORCEPROP 0 LASTPIN (5050 925) $PN BR86
J 0
(5060 935);
DISPLAY 0.680851 (5060 935);
PAINT MONO (5060 935);
FORCEPROP 0 LASTPIN (5050 975) $PN BR88
J 0
(5060 985);
DISPLAY 0.680851 (5060 985);
PAINT MONO (5060 985);
FORCEPROP 0 LASTPIN (5050 1025) $PN BR90
J 0
(5060 1035);
DISPLAY 0.680851 (5060 1035);
PAINT MONO (5060 1035);
FORCEPROP 0 LASTPIN (5050 1175) $PN BT12
J 0
(5060 1185);
DISPLAY 0.680851 (5060 1185);
PAINT MONO (5060 1185);
FORCEPROP 0 LASTPIN (5050 1225) $PN BT16
J 0
(5060 1235);
DISPLAY 0.680851 (5060 1235);
PAINT MONO (5060 1235);
FORCEPROP 0 LASTPIN (5050 1275) $PN BT20
J 0
(5060 1285);
DISPLAY 0.680851 (5060 1285);
PAINT MONO (5060 1285);
FORCEPROP 0 LASTPIN (5050 1075) $PN BT4
J 0
(5060 1085);
DISPLAY 0.680851 (5060 1085);
PAINT MONO (5060 1085);
FORCEPROP 0 LASTPIN (5050 1125) $PN BT8
J 0
(5060 1135);
DISPLAY 0.680851 (5060 1135);
PAINT MONO (5060 1135);
FORCEPROP 0 LASTPIN (5050 1375) $PN BU15
J 0
(5060 1385);
DISPLAY 0.680851 (5060 1385);
PAINT MONO (5060 1385);
FORCEPROP 0 LASTPIN (5050 1425) $PN BU19
J 0
(5060 1435);
DISPLAY 0.680851 (5060 1435);
PAINT MONO (5060 1435);
FORCEPROP 0 LASTPIN (5050 1475) $PN BU21
J 0
(5060 1485);
DISPLAY 0.680851 (5060 1485);
PAINT MONO (5060 1485);
FORCEPROP 0 LASTPIN (5050 1525) $PN BU23
J 0
(5060 1535);
DISPLAY 0.680851 (5060 1535);
PAINT MONO (5060 1535);
FORCEPROP 0 LASTPIN (5050 1575) $PN BU25
J 0
(5060 1585);
DISPLAY 0.680851 (5060 1585);
PAINT MONO (5060 1585);
FORCEPROP 0 LASTPIN (5050 1625) $PN BU31
J 0
(5060 1635);
DISPLAY 0.680851 (5060 1635);
PAINT MONO (5060 1635);
FORCEPROP 0 LASTPIN (5050 1325) $PN BU7
J 0
(5060 1335);
DISPLAY 0.680851 (5060 1335);
PAINT MONO (5060 1335);
FORCEPROP 0 LASTPIN (5050 1875) $PN BV12
J 0
(5060 1885);
DISPLAY 0.680851 (5060 1885);
PAINT MONO (5060 1885);
FORCEPROP 0 LASTPIN (5050 1925) $PN BV16
J 0
(5060 1935);
DISPLAY 0.680851 (5060 1935);
PAINT MONO (5060 1935);
FORCEPROP 0 LASTPIN (5050 1975) $PN BV18
J 0
(5060 1985);
DISPLAY 0.680851 (5060 1985);
PAINT MONO (5060 1985);
FORCEPROP 0 LASTPIN (5050 1675) $PN BV2
J 0
(5060 1685);
DISPLAY 0.680851 (5060 1685);
PAINT MONO (5060 1685);
FORCEPROP 0 LASTPIN (5050 2025) $PN BV20
J 0
(5060 2035);
DISPLAY 0.680851 (5060 2035);
PAINT MONO (5060 2035);
FORCEPROP 0 LASTPIN (5050 1725) $PN BV4
J 0
(5060 1735);
DISPLAY 0.680851 (5060 1735);
PAINT MONO (5060 1735);
FORCEPROP 0 LASTPIN (5050 1775) $PN BV6
J 0
(5060 1785);
DISPLAY 0.680851 (5060 1785);
PAINT MONO (5060 1785);
FORCEPROP 0 LASTPIN (5050 1825) $PN BV8
J 0
(5060 1835);
DISPLAY 0.680851 (5060 1835);
PAINT MONO (5060 1835);
FORCEPROP 0 LASTPIN (5050 2225) $PN BW13
J 0
(5060 2235);
DISPLAY 0.680851 (5060 2235);
PAINT MONO (5060 2235);
FORCEPROP 0 LASTPIN (5050 2275) $PN BW17
J 0
(5060 2285);
DISPLAY 0.680851 (5060 2285);
PAINT MONO (5060 2285);
FORCEPROP 0 LASTPIN (5050 2325) $PN BW27
J 0
(5060 2335);
DISPLAY 0.680851 (5060 2335);
PAINT MONO (5060 2335);
FORCEPROP 0 LASTPIN (5050 2375) $PN BW29
J 0
(5060 2385);
DISPLAY 0.680851 (5060 2385);
PAINT MONO (5060 2385);
FORCEPROP 0 LASTPIN (5050 2075) $PN BW3
J 0
(5060 2085);
DISPLAY 0.680851 (5060 2085);
PAINT MONO (5060 2085);
FORCEPROP 0 LASTPIN (5050 2425) $PN BW31
J 0
(5060 2435);
DISPLAY 0.680851 (5060 2435);
PAINT MONO (5060 2435);
FORCEPROP 0 LASTPIN (5050 2125) $PN BW5
J 0
(5060 2135);
DISPLAY 0.680851 (5060 2135);
PAINT MONO (5060 2135);
FORCEPROP 0 LASTPIN (5050 2175) $PN BW9
J 0
(5060 2185);
DISPLAY 0.680851 (5060 2185);
PAINT MONO (5060 2185);
FORCEPROP 0 LASTPIN (5050 2575) $PN BY12
J 0
(5060 2585);
DISPLAY 0.680851 (5060 2585);
PAINT MONO (5060 2585);
FORCEPROP 0 LASTPIN (5050 2625) $PN BY16
J 0
(5060 2635);
DISPLAY 0.680851 (5060 2635);
PAINT MONO (5060 2635);
FORCEPROP 0 LASTPIN (5050 2675) $PN BY20
J 0
(5060 2685);
DISPLAY 0.680851 (5060 2685);
PAINT MONO (5060 2685);
FORCEPROP 0 LASTPIN (5050 2475) $PN BY4
J 0
(5060 2485);
DISPLAY 0.680851 (5060 2485);
PAINT MONO (5060 2485);
FORCEPROP 0 LASTPIN (5050 2525) $PN BY8
J 0
(5060 2535);
DISPLAY 0.680851 (5060 2535);
PAINT MONO (5060 2535);
FORCEPROP 0 LASTPIN (5050 2725) $PN CA3
J 0
(5060 2735);
DISPLAY 0.680851 (5060 2735);
PAINT MONO (5060 2735);
FORCEPROP 0 LASTPIN (5050 2775) $PN CA31
J 0
(5060 2785);
DISPLAY 0.680851 (5060 2785);
PAINT MONO (5060 2785);
FORCEPROP 0 LASTPIN (5050 2925) $PN CB12
J 0
(5060 2935);
DISPLAY 0.680851 (5060 2935);
PAINT MONO (5060 2935);
FORCEPROP 0 LASTPIN (5050 2975) $PN CB16
J 0
(5060 2985);
DISPLAY 0.680851 (5060 2985);
PAINT MONO (5060 2985);
FORCEPROP 0 LASTPIN (5050 3025) $PN CB20
J 0
(5060 3035);
DISPLAY 0.680851 (5060 3035);
PAINT MONO (5060 3035);
FORCEPROP 0 LASTPIN (5050 3075) $PN CB22
J 0
(5060 3085);
DISPLAY 0.680851 (5060 3085);
PAINT MONO (5060 3085);
FORCEPROP 0 LASTPIN (5050 3125) $PN CB24
J 0
(5060 3135);
DISPLAY 0.680851 (5060 3135);
PAINT MONO (5060 3135);
FORCEPROP 0 LASTPIN (5050 3175) $PN CB26
J 0
(5060 3185);
DISPLAY 0.680851 (5060 3185);
PAINT MONO (5060 3185);
FORCEPROP 0 LASTPIN (5050 3225) $PN CB28
J 0
(5060 3235);
DISPLAY 0.680851 (5060 3235);
PAINT MONO (5060 3235);
FORCEPROP 0 LASTPIN (5050 3275) $PN CB32
J 0
(5060 3285);
DISPLAY 0.680851 (5060 3285);
PAINT MONO (5060 3285);
FORCEPROP 0 LASTPIN (5050 3325) $PN CB34
J 0
(5060 3335);
DISPLAY 0.680851 (5060 3335);
PAINT MONO (5060 3335);
FORCEPROP 0 LASTPIN (5050 3375) $PN CB36
J 0
(5060 3385);
DISPLAY 0.680851 (5060 3385);
PAINT MONO (5060 3385);
FORCEPROP 0 LASTPIN (5050 3425) $PN CB38
J 0
(5060 3435);
DISPLAY 0.680851 (5060 3435);
PAINT MONO (5060 3435);
FORCEPROP 0 LASTPIN (5050 2825) $PN CB4
J 0
(5060 2835);
DISPLAY 0.680851 (5060 2835);
PAINT MONO (5060 2835);
FORCEPROP 0 LASTPIN (5050 3475) $PN CB40
J 0
(5060 3485);
DISPLAY 0.680851 (5060 3485);
PAINT MONO (5060 3485);
FORCEPROP 0 LASTPIN (5050 3525) $PN CB42
J 0
(5060 3535);
DISPLAY 0.680851 (5060 3535);
PAINT MONO (5060 3535);
FORCEPROP 0 LASTPIN (5050 3575) $PN CB44
J 0
(5060 3585);
DISPLAY 0.680851 (5060 3585);
PAINT MONO (5060 3585);
FORCEPROP 0 LASTPIN (5050 3625) $PN CB47
J 0
(5060 3635);
DISPLAY 0.680851 (5060 3635);
PAINT MONO (5060 3635);
FORCEPROP 0 LASTPIN (5050 3675) $PN CB49
J 0
(5060 3685);
DISPLAY 0.680851 (5060 3685);
PAINT MONO (5060 3685);
FORCEPROP 0 LASTPIN (5050 3725) $PN CB51
J 0
(5060 3735);
DISPLAY 0.680851 (5060 3735);
PAINT MONO (5060 3735);
FORCEPROP 0 LASTPIN (5050 3775) $PN CB53
J 0
(5060 3785);
DISPLAY 0.680851 (5060 3785);
PAINT MONO (5060 3785);
FORCEPROP 0 LASTPIN (2650 -175) $PN CB55
J 2
(2640 -165);
DISPLAY 0.680851 (2640 -165);
PAINT MONO (2640 -165);
FORCEPROP 0 LASTPIN (2650 -125) $PN CB57
J 2
(2640 -115);
DISPLAY 0.680851 (2640 -115);
PAINT MONO (2640 -115);
FORCEPROP 0 LASTPIN (2650 -75) $PN CB59
J 2
(2640 -65);
DISPLAY 0.680851 (2640 -65);
PAINT MONO (2640 -65);
FORCEPROP 0 LASTPIN (2650 -25) $PN CB63
J 2
(2640 -15);
DISPLAY 0.680851 (2640 -15);
PAINT MONO (2640 -15);
FORCEPROP 0 LASTPIN (2650 25) $PN CB65
J 2
(2640 35);
DISPLAY 0.680851 (2640 35);
PAINT MONO (2640 35);
FORCEPROP 0 LASTPIN (2650 75) $PN CB67
J 2
(2640 85);
DISPLAY 0.680851 (2640 85);
PAINT MONO (2640 85);
FORCEPROP 0 LASTPIN (2650 125) $PN CB69
J 2
(2640 135);
DISPLAY 0.680851 (2640 135);
PAINT MONO (2640 135);
FORCEPROP 0 LASTPIN (2650 175) $PN CB71
J 2
(2640 185);
DISPLAY 0.680851 (2640 185);
PAINT MONO (2640 185);
FORCEPROP 0 LASTPIN (2650 225) $PN CB73
J 2
(2640 235);
DISPLAY 0.680851 (2640 235);
PAINT MONO (2640 235);
FORCEPROP 0 LASTPIN (2650 275) $PN CB79
J 2
(2640 285);
DISPLAY 0.680851 (2640 285);
PAINT MONO (2640 285);
FORCEPROP 0 LASTPIN (5050 2875) $PN CB8
J 0
(5060 2885);
DISPLAY 0.680851 (5060 2885);
PAINT MONO (5060 2885);
FORCEPROP 0 LASTPIN (2650 325) $PN CB81
J 2
(2640 335);
DISPLAY 0.680851 (2640 335);
PAINT MONO (2640 335);
FORCEPROP 0 LASTPIN (2650 375) $PN CB83
J 2
(2640 385);
DISPLAY 0.680851 (2640 385);
PAINT MONO (2640 385);
FORCEPROP 0 LASTPIN (2650 425) $PN CB85
J 2
(2640 435);
DISPLAY 0.680851 (2640 435);
PAINT MONO (2640 435);
FORCEPROP 0 LASTPIN (2650 475) $PN CB87
J 2
(2640 485);
DISPLAY 0.680851 (2640 485);
PAINT MONO (2640 485);
FORCEPROP 0 LASTPIN (2650 525) $PN CB89
J 2
(2640 535);
DISPLAY 0.680851 (2640 535);
PAINT MONO (2640 535);
FORCEPROP 0 LASTPIN (2650 675) $PN CC13
J 2
(2640 685);
DISPLAY 0.680851 (2640 685);
PAINT MONO (2640 685);
FORCEPROP 0 LASTPIN (2650 725) $PN CC17
J 2
(2640 735);
DISPLAY 0.680851 (2640 735);
PAINT MONO (2640 735);
FORCEPROP 0 LASTPIN (2650 775) $PN CC31
J 2
(2640 785);
DISPLAY 0.680851 (2640 785);
PAINT MONO (2640 785);
FORCEPROP 0 LASTPIN (2650 575) $PN CC5
J 2
(2640 585);
DISPLAY 0.680851 (2640 585);
PAINT MONO (2640 585);
FORCEPROP 0 LASTPIN (2650 825) $PN CC62
J 2
(2640 835);
DISPLAY 0.680851 (2640 835);
PAINT MONO (2640 835);
FORCEPROP 0 LASTPIN (2650 875) $PN CC70
J 2
(2640 885);
DISPLAY 0.680851 (2640 885);
PAINT MONO (2640 885);
FORCEPROP 0 LASTPIN (2650 925) $PN CC72
J 2
(2640 935);
DISPLAY 0.680851 (2640 935);
PAINT MONO (2640 935);
FORCEPROP 0 LASTPIN (2650 975) $PN CC74
J 2
(2640 985);
DISPLAY 0.680851 (2640 985);
PAINT MONO (2640 985);
FORCEPROP 0 LASTPIN (2650 625) $PN CC9
J 2
(2640 635);
DISPLAY 0.680851 (2640 635);
PAINT MONO (2640 635);
FORCEPROP 0 LASTPIN (2650 1125) $PN CD12
J 2
(2640 1135);
DISPLAY 0.680851 (2640 1135);
PAINT MONO (2640 1135);
FORCEPROP 0 LASTPIN (2650 1175) $PN CD16
J 2
(2640 1185);
DISPLAY 0.680851 (2640 1185);
PAINT MONO (2640 1185);
FORCEPROP 0 LASTPIN (2650 1225) $PN CD20
J 2
(2640 1235);
DISPLAY 0.680851 (2640 1235);
PAINT MONO (2640 1235);
FORCEPROP 0 LASTPIN (2650 1025) $PN CD4
J 2
(2640 1035);
DISPLAY 0.680851 (2640 1035);
PAINT MONO (2640 1035);
FORCEPROP 0 LASTPIN (2650 1275) $PN CD61
J 2
(2640 1285);
DISPLAY 0.680851 (2640 1285);
PAINT MONO (2640 1285);
FORCEPROP 0 LASTPIN (2650 1325) $PN CD75
J 2
(2640 1335);
DISPLAY 0.680851 (2640 1335);
PAINT MONO (2640 1335);
FORCEPROP 0 LASTPIN (2650 1375) $PN CD77
J 2
(2640 1385);
DISPLAY 0.680851 (2640 1385);
PAINT MONO (2640 1385);
FORCEPROP 0 LASTPIN (2650 1075) $PN CD8
J 2
(2640 1085);
DISPLAY 0.680851 (2640 1085);
PAINT MONO (2640 1085);
FORCEPROP 0 LASTPIN (2650 1425) $PN CE3
J 2
(2640 1435);
DISPLAY 0.680851 (2640 1435);
PAINT MONO (2640 1435);
FORCEPROP 0 LASTPIN (2650 1475) $PN CE60
J 2
(2640 1485);
DISPLAY 0.680851 (2640 1485);
PAINT MONO (2640 1485);
FORCEPROP 0 LASTPIN (2650 1525) $PN CE66
J 2
(2640 1535);
DISPLAY 0.680851 (2640 1535);
PAINT MONO (2640 1535);
FORCEPROP 0 LASTPIN (2650 1575) $PN CE72
J 2
(2640 1585);
DISPLAY 0.680851 (2640 1585);
PAINT MONO (2640 1585);
FORCEPROP 0 LASTPIN (2650 1625) $PN CE76
J 2
(2640 1635);
DISPLAY 0.680851 (2640 1635);
PAINT MONO (2640 1635);
FORCEPROP 0 LASTPIN (2650 1675) $PN CE78
J 2
(2640 1685);
DISPLAY 0.680851 (2640 1685);
PAINT MONO (2640 1685);
FORCEPROP 0 LASTPIN (2650 1825) $PN CF12
J 2
(2640 1835);
DISPLAY 0.680851 (2640 1835);
PAINT MONO (2640 1835);
FORCEPROP 0 LASTPIN (2650 1875) $PN CF16
J 2
(2640 1885);
DISPLAY 0.680851 (2640 1885);
PAINT MONO (2640 1885);
FORCEPROP 0 LASTPIN (2650 1925) $PN CF20
J 2
(2640 1935);
DISPLAY 0.680851 (2640 1935);
PAINT MONO (2640 1935);
FORCEPROP 0 LASTPIN (2650 1725) $PN CF4
J 2
(2640 1735);
DISPLAY 0.680851 (2640 1735);
PAINT MONO (2640 1735);
FORCEPROP 0 LASTPIN (2650 1975) $PN CF69
J 2
(2640 1985);
DISPLAY 0.680851 (2640 1985);
PAINT MONO (2640 1985);
FORCEPROP 0 LASTPIN (2650 2025) $PN CF71
J 2
(2640 2035);
DISPLAY 0.680851 (2640 2035);
PAINT MONO (2640 2035);
FORCEPROP 0 LASTPIN (2650 1775) $PN CF8
J 2
(2640 1785);
DISPLAY 0.680851 (2640 1785);
PAINT MONO (2640 1785);
FORCEPROP 0 LASTPIN (2650 2075) $PN CG1
J 2
(2640 2085);
DISPLAY 0.680851 (2640 2085);
PAINT MONO (2640 2085);
FORCEPROP 0 LASTPIN (2650 2225) $PN CG13
J 2
(2640 2235);
DISPLAY 0.680851 (2640 2235);
PAINT MONO (2640 2235);
FORCEPROP 0 LASTPIN (2650 2275) $PN CG17
J 2
(2640 2285);
DISPLAY 0.680851 (2640 2285);
PAINT MONO (2640 2285);
FORCEPROP 0 LASTPIN (2650 2325) $PN CG21
J 2
(2640 2335);
DISPLAY 0.680851 (2640 2335);
PAINT MONO (2640 2335);
FORCEPROP 0 LASTPIN (2650 2375) $PN CG23
J 2
(2640 2385);
DISPLAY 0.680851 (2640 2385);
PAINT MONO (2640 2385);
FORCEPROP 0 LASTPIN (2650 2425) $PN CG25
J 2
(2640 2435);
DISPLAY 0.680851 (2640 2435);
PAINT MONO (2640 2435);
FORCEPROP 0 LASTPIN (2650 2125) $PN CG5
J 2
(2640 2135);
DISPLAY 0.680851 (2640 2135);
PAINT MONO (2640 2135);
FORCEPROP 0 LASTPIN (2650 2475) $PN CG62
J 2
(2640 2485);
DISPLAY 0.680851 (2640 2485);
PAINT MONO (2640 2485);
FORCEPROP 0 LASTPIN (2650 2525) $PN CG64
J 2
(2640 2535);
DISPLAY 0.680851 (2640 2535);
PAINT MONO (2640 2535);
FORCEPROP 0 LASTPIN (2650 2575) $PN CG70
J 2
(2640 2585);
DISPLAY 0.680851 (2640 2585);
PAINT MONO (2640 2585);
FORCEPROP 0 LASTPIN (2650 2625) $PN CG72
J 2
(2640 2635);
DISPLAY 0.680851 (2640 2635);
PAINT MONO (2640 2635);
FORCEPROP 0 LASTPIN (2650 2675) $PN CG74
J 2
(2640 2685);
DISPLAY 0.680851 (2640 2685);
PAINT MONO (2640 2685);
FORCEPROP 0 LASTPIN (2650 2725) $PN CG78
J 2
(2640 2735);
DISPLAY 0.680851 (2640 2735);
PAINT MONO (2640 2735);
FORCEPROP 0 LASTPIN (2650 2175) $PN CG9
J 2
(2640 2185);
DISPLAY 0.680851 (2640 2185);
PAINT MONO (2640 2185);
FORCEPROP 0 LASTPIN (2650 2875) $PN CH12
J 2
(2640 2885);
DISPLAY 0.680851 (2640 2885);
PAINT MONO (2640 2885);
FORCEPROP 0 LASTPIN (2650 2925) $PN CH16
J 2
(2640 2935);
DISPLAY 0.680851 (2640 2935);
PAINT MONO (2640 2935);
FORCEPROP 0 LASTPIN (2650 2975) $PN CH20
J 2
(2640 2985);
DISPLAY 0.680851 (2640 2985);
PAINT MONO (2640 2985);
FORCEPROP 0 LASTPIN (2650 2775) $PN CH4
J 2
(2640 2785);
DISPLAY 0.680851 (2640 2785);
PAINT MONO (2640 2785);
FORCEPROP 0 LASTPIN (2650 3025) $PN CH67
J 2
(2640 3035);
DISPLAY 0.680851 (2640 3035);
PAINT MONO (2640 3035);
FORCEPROP 0 LASTPIN (2650 3075) $PN CH73
J 2
(2640 3085);
DISPLAY 0.680851 (2640 3085);
PAINT MONO (2640 3085);
FORCEPROP 0 LASTPIN (2650 3125) $PN CH79
J 2
(2640 3135);
DISPLAY 0.680851 (2640 3135);
PAINT MONO (2640 3135);
FORCEPROP 0 LASTPIN (2650 2825) $PN CH8
J 2
(2640 2835);
DISPLAY 0.680851 (2640 2835);
PAINT MONO (2640 2835);
FORCEPROP 0 LASTPIN (2650 3175) $PN CH83
J 2
(2640 3185);
DISPLAY 0.680851 (2640 3185);
PAINT MONO (2640 3185);
FORCEPROP 0 LASTPIN (2650 3225) $PN CH85
J 2
(2640 3235);
DISPLAY 0.680851 (2640 3235);
PAINT MONO (2640 3235);
FORCEPROP 0 LASTPIN (2650 3275) $PN CH87
J 2
(2640 3285);
DISPLAY 0.680851 (2640 3285);
PAINT MONO (2640 3285);
FORCEPROP 0 LASTPIN (2650 3325) $PN CH89
J 2
(2640 3335);
DISPLAY 0.680851 (2640 3335);
PAINT MONO (2640 3335);
FORCEPROP 0 LASTPIN (2650 3375) $PN CJ60
J 2
(2640 3385);
DISPLAY 0.680851 (2640 3385);
PAINT MONO (2640 3385);
FORCEPROP 0 LASTPIN (2650 3475) $PN CJ80
J 2
(2640 3485);
DISPLAY 0.680851 (2640 3485);
PAINT MONO (2640 3485);
FORCEPROP 0 LASTPIN (2650 3625) $PN CK12
J 2
(2640 3635);
DISPLAY 0.680851 (2640 3635);
PAINT MONO (2640 3635);
FORCEPROP 0 LASTPIN (2650 3675) $PN CK16
J 2
(2640 3685);
DISPLAY 0.680851 (2640 3685);
PAINT MONO (2640 3685);
FORCEPROP 0 LASTPIN (2650 3725) $PN CK20
J 2
(2640 3735);
DISPLAY 0.680851 (2640 3735);
PAINT MONO (2640 3735);
FORCEPROP 0 LASTPIN (2650 3775) $PN CK26
J 2
(2640 3785);
DISPLAY 0.680851 (2640 3785);
PAINT MONO (2640 3785);
FORCEPROP 0 LASTPIN (2650 3575) $PN CK8
J 2
(2640 3585);
DISPLAY 0.680851 (2640 3585);
PAINT MONO (2640 3585);
FORCEPROP 2 LAST CDS_LIB pure_quanta
J 0
(3850 1800);
DISPLAY INVISIBLE (3850 1800);
FORCEPROP 1 LAST NEEDS_NO_SIZE TRUE
J 0
(3850 1800);
DISPLAY 0.723404 (3850 1800);
PAINT GREEN (3850 1800);
DISPLAY INVISIBLE (3850 1800);
FORCEPROP 1 LAST CDS_LMAN_SYM_OUTLINE -1050,2150,1050,-2100
J 0
(3850 1800);
DISPLAY 0.468085 (3850 1800);
PAINT GREEN (3850 1800);
DISPLAY INVISIBLE (3850 1800);
FORCEPROP 2 LAST CDS_LOCATION U2
J 0
(2800 4275);
DISPLAY 1.021277 (2800 4275);
DISPLAY INVISIBLE (2800 4275);
FORCEPROP 0 LAST $SEC 36
J 0
(2800 4275);
DISPLAY 0.680851 (2800 4275);
PAINT MONO (2800 4275);
DISPLAY INVISIBLE (2800 4275);
FORCEPROP 2 LAST CDS_SEC 36
J 0
(2800 4275);
DISPLAY 1.021277 (2800 4275);
DISPLAY INVISIBLE (2800 4275);
FORCEPROP 1 LAST PATH I12
J 0
(3850 1800);
DISPLAY 0.723404 (3850 1800);
PAINT GREEN (3850 1800);
DISPLAY INVISIBLE (3850 1800);
FORCEADD UNIVERSAL_GND..1
(-775 -725);
FORCEPROP 3 LASTPIN (-775 -675) SIG_NAME GND\g
J 0
(-765 -665);
DISPLAY 0.659574 (-765 -665);
PAINT MONO (-765 -665);
DISPLAY INVISIBLE (-765 -665);
FORCEPROP 2 LAST CDS_LIB logical_power
J 0
(-775 -725);
PAINT MONO (-775 -725);
DISPLAY INVISIBLE (-775 -725);
FORCEPROP 1 LAST HDL_POWER GND
J 1
(-750 -800);
DISPLAY 0.872340 (-750 -800);
PAINT GREEN (-750 -800);
DISPLAY INVISIBLE (-750 -800);
FORCEPROP 1 LAST PATH I3
J 0
(-700 -725);
DISPLAY 0.872340 (-700 -725);
PAINT AQUA (-700 -725);
DISPLAY INVISIBLE (-700 -725);
FORCEADD UNIVERSAL_GND..1
(-625 -725);
FORCEPROP 3 LASTPIN (-625 -675) SIG_NAME GND\g
J 0
(-615 -665);
DISPLAY 0.659574 (-615 -665);
PAINT MONO (-615 -665);
DISPLAY INVISIBLE (-615 -665);
FORCEPROP 2 LAST CDS_LIB logical_power
J 0
(-625 -725);
PAINT MONO (-625 -725);
DISPLAY INVISIBLE (-625 -725);
FORCEPROP 1 LAST HDL_POWER GND
J 1
(-600 -800);
DISPLAY 0.872340 (-600 -800);
PAINT GREEN (-600 -800);
DISPLAY INVISIBLE (-600 -800);
FORCEPROP 1 LAST PATH I4
J 0
(-550 -725);
DISPLAY 0.872340 (-550 -725);
PAINT AQUA (-550 -725);
DISPLAY INVISIBLE (-550 -725);
FORCEADD UNIVERSAL_GND..1
(2275 -725);
FORCEPROP 3 LASTPIN (2275 -675) SIG_NAME GND\g
J 0
(2285 -665);
DISPLAY 0.659574 (2285 -665);
PAINT MONO (2285 -665);
DISPLAY INVISIBLE (2285 -665);
FORCEPROP 2 LAST CDS_LIB logical_power
J 0
(2275 -725);
PAINT MONO (2275 -725);
DISPLAY INVISIBLE (2275 -725);
FORCEPROP 1 LAST HDL_POWER GND
J 1
(2300 -800);
DISPLAY 0.872340 (2300 -800);
PAINT GREEN (2300 -800);
DISPLAY INVISIBLE (2300 -800);
FORCEPROP 1 LAST PATH I6
J 0
(2350 -725);
DISPLAY 0.872340 (2350 -725);
PAINT AQUA (2350 -725);
DISPLAY INVISIBLE (2350 -725);
FORCEADD UNIVERSAL_GND..1
(2400 -725);
FORCEPROP 3 LASTPIN (2400 -675) SIG_NAME GND\g
J 0
(2410 -665);
DISPLAY 0.659574 (2410 -665);
PAINT MONO (2410 -665);
DISPLAY INVISIBLE (2410 -665);
FORCEPROP 2 LAST CDS_LIB logical_power
J 0
(2400 -725);
PAINT MONO (2400 -725);
DISPLAY INVISIBLE (2400 -725);
FORCEPROP 1 LAST HDL_POWER GND
J 1
(2425 -800);
DISPLAY 0.872340 (2425 -800);
PAINT GREEN (2425 -800);
DISPLAY INVISIBLE (2425 -800);
FORCEPROP 1 LAST PATH I7
J 0
(2475 -725);
DISPLAY 0.872340 (2475 -725);
PAINT AQUA (2475 -725);
DISPLAY INVISIBLE (2475 -725);
FORCEADD UNIVERSAL_GND..1
(5300 -725);
FORCEPROP 3 LASTPIN (5300 -675) SIG_NAME GND\g
J 0
(5310 -665);
DISPLAY 0.659574 (5310 -665);
PAINT MONO (5310 -665);
DISPLAY INVISIBLE (5310 -665);
FORCEPROP 2 LAST CDS_LIB logical_power
J 0
(5300 -725);
PAINT MONO (5300 -725);
DISPLAY INVISIBLE (5300 -725);
FORCEPROP 1 LAST HDL_POWER GND
J 1
(5325 -800);
DISPLAY 0.872340 (5325 -800);
PAINT GREEN (5325 -800);
DISPLAY INVISIBLE (5325 -800);
FORCEPROP 1 LAST PATH I9
J 0
(5375 -725);
DISPLAY 0.872340 (5375 -725);
PAINT AQUA (5375 -725);
DISPLAY INVISIBLE (5375 -725);
FORCEADD QUANTA_TITLE_BLOCK_C..1
(5500 -1575);
FORCEPROP 0 LAST CDS_CON_LAST_MODIFIED Fri Aug 25 14:00:23 2023
J 0
(3615 -1560);
PAINT MONO (3615 -1560);
DISPLAY INVISIBLE (3615 -1560);
FORCEPROP 1 LAST CUSTOM_TXT_CDS <CON_LAST_MODIFIED>
J 0
(3615 -1560);
DISPLAY 0.978723 (3615 -1560);
FORCEPROP 2 LAST CUSTOM_TXT_CDS <XR_PAGE_TITLE>
J 0
(-2390 3675);
DISPLAY 0.638298 (-2390 3675);
PAINT PINK (-2390 3675);
DISPLAY INVISIBLE (-2390 3675);
FORCEPROP 2 LAST CUSTOM_TXT_CDS <Q_NUMBER>
J 0
(4097 -1472);
DISPLAY 1.212766 (4097 -1472);
FORCEPROP 1 LAST CUSTOM_TXT_CDS <NAME_2>
J 0
(2325 -1525);
FORCEPROP 1 LAST CUSTOM_TXT_CDS <NAME_1>
J 0
(2325 -1400);
FORCEPROP 1 LAST CUSTOM_TXT_CDS <Q_PROJ>
J 0
(3118 -1473);
DISPLAY 1.212766 (3118 -1473);
FORCEPROP 1 LAST CUSTOM_TXT_CDS <Q_REV>
J 0
(5316 -1472);
DISPLAY 1.212766 (5316 -1472);
FORCEPROP 1 LAST CUSTOM_TXT_CDS <CON_PAGE_NUM> OF <CON_TOTAL_PAGES>
J 0
(5054 -1557);
DISPLAY 0.978723 (5054 -1557);
FORCEPROP 1 LAST Q_TITLE SPR CPU0 POWER - GND (28 OF 30)
J 0
(-3866 -1549);
DISPLAY 1.957447 (-3866 -1549);
PAINT GREEN (-3866 -1549);
FORCEPROP 1 LAST Q_DEPT 
J 1
(1737 -1526);
DISPLAY 1.957447 (1737 -1526);
PAINT GREEN (1737 -1526);
FORCEPROP 2 LAST PAGE_BORDER TRUE
J 0
(-2390 3675);
DISPLAY 0.638298 (-2390 3675);
PAINT PINK (-2390 3675);
DISPLAY INVISIBLE (-2390 3675);
FORCEPROP 1 LAST CDS_LMAN_SYM_OUTLINE -9475,6775,100,-125
J 0
(5500 -1575);
DISPLAY 0.468085 (5500 -1575);
PAINT GREEN (5500 -1575);
DISPLAY INVISIBLE (5500 -1575);
FORCEPROP 2 LAST CDS_LIB pure_quanta
J 0
(5500 -1575);
PAINT MONO (5500 -1575);
DISPLAY INVISIBLE (5500 -1575);
FORCEPROP 2 LAST CDS_XR_PAGE_TITLE CR-40 : @S9S_MB_2U_LIB.S9S_MB_2U(SCH_1):PAGE40
J 0
(-2390 3675);
DISPLAY 0.638298 (-2390 3675);
PAINT PINK (-2390 3675);
DISPLAY INVISIBLE (-2390 3675);
FORCEPROP 1 LAST COMMENT_BODY TRUE
J 0
(5512 -1588);
DISPLAY 0.978723 (5512 -1588);
PAINT GREEN (5512 -1588);
DISPLAY INVISIBLE (5512 -1588);
WIRE 16 -1 (5300 -175)(5300 -675);
WIRE 16 -1 (5300 -125)(5300 -175);
WIRE 16 -1 (5050 -175)(5300 -175);
WIRE 16 -1 (2400 -175)(2400 -675);
WIRE 16 -1 (2400 -125)(2400 -175);
WIRE 16 -1 (2400 -175)(2650 -175);
WIRE 16 -1 (2275 -175)(2275 -675);
WIRE 16 -1 (2275 -125)(2275 -175);
WIRE 16 -1 (2025 -175)(2275 -175);
WIRE 16 -1 (-625 -175)(-625 -675);
WIRE 16 -1 (-625 -125)(-625 -175);
WIRE 16 -1 (-625 -175)(-375 -175);
WIRE 16 -1 (-775 -175)(-775 -675);
WIRE 16 -1 (-775 -125)(-775 -175);
WIRE 16 -1 (-1025 -175)(-775 -175);
WIRE 16 -1 (-3675 -175)(-3675 -675);
WIRE 16 -1 (-3675 -125)(-3675 -175);
WIRE 16 -1 (-3675 -175)(-3425 -175);
WIRE 16 -1 (2025 -125)(2275 -125);
WIRE 16 -1 (2025 -75)(2275 -75);
WIRE 16 -1 (2275 -125)(2275 -75);
WIRE 16 -1 (2025 -25)(2275 -25);
WIRE 16 -1 (2275 -25)(2275 -75);
WIRE 16 -1 (2275 25)(2275 -25);
WIRE 16 -1 (2025 25)(2275 25);
WIRE 16 -1 (2025 75)(2275 75);
WIRE 16 -1 (2275 75)(2275 25);
WIRE 16 -1 (2025 125)(2275 125);
WIRE 16 -1 (2275 125)(2275 75);
WIRE 16 -1 (2025 175)(2275 175);
WIRE 16 -1 (2275 175)(2275 125);
WIRE 16 -1 (2025 225)(2275 225);
WIRE 16 -1 (2275 225)(2275 175);
WIRE 16 -1 (2275 275)(2025 275);
WIRE 16 -1 (2275 275)(2275 225);
WIRE 16 -1 (2275 325)(2025 325);
WIRE 16 -1 (2275 325)(2275 275);
WIRE 16 -1 (2275 375)(2025 375);
WIRE 16 -1 (2275 375)(2275 325);
WIRE 16 -1 (2025 425)(2275 425);
WIRE 16 -1 (2275 375)(2275 425);
WIRE 16 -1 (2275 475)(2025 475);
WIRE 16 -1 (2275 425)(2275 475);
WIRE 16 -1 (2275 525)(2025 525);
WIRE 16 -1 (2275 525)(2275 475);
WIRE 16 -1 (2275 575)(2025 575);
WIRE 16 -1 (2275 575)(2275 525);
WIRE 16 -1 (2275 625)(2025 625);
WIRE 16 -1 (2275 625)(2275 575);
WIRE 16 -1 (2025 675)(2275 675);
WIRE 16 -1 (2275 675)(2275 625);
WIRE 16 -1 (2025 725)(2275 725);
WIRE 16 -1 (2275 725)(2275 675);
WIRE 16 -1 (2025 775)(2275 775);
WIRE 16 -1 (2275 725)(2275 775);
WIRE 16 -1 (2025 825)(2275 825);
WIRE 16 -1 (2275 825)(2275 775);
WIRE 16 -1 (2025 875)(2275 875);
WIRE 16 -1 (2275 875)(2275 825);
WIRE 16 -1 (2025 925)(2275 925);
WIRE 16 -1 (2275 925)(2275 875);
WIRE 16 -1 (2025 975)(2275 975);
WIRE 16 -1 (2275 975)(2275 925);
WIRE 16 -1 (2025 1025)(2275 1025);
WIRE 16 -1 (2275 1025)(2275 975);
WIRE 16 -1 (2025 1075)(2275 1075);
WIRE 16 -1 (2275 1075)(2275 1025);
WIRE 16 -1 (2275 1125)(2025 1125);
WIRE 16 -1 (2275 1125)(2275 1075);
WIRE 16 -1 (2275 1175)(2025 1175);
WIRE 16 -1 (2275 1175)(2275 1125);
WIRE 16 -1 (2275 1225)(2025 1225);
WIRE 16 -1 (2275 1225)(2275 1175);
WIRE 16 -1 (2025 1275)(2275 1275);
WIRE 16 -1 (2275 1225)(2275 1275);
WIRE 16 -1 (2275 1325)(2025 1325);
WIRE 16 -1 (2275 1275)(2275 1325);
WIRE 16 -1 (2275 1375)(2025 1375);
WIRE 16 -1 (2275 1375)(2275 1325);
WIRE 16 -1 (2275 1425)(2025 1425);
WIRE 16 -1 (2275 1425)(2275 1375);
WIRE 16 -1 (2275 1475)(2025 1475);
WIRE 16 -1 (2275 1475)(2275 1425);
WIRE 16 -1 (2025 1525)(2275 1525);
WIRE 16 -1 (2275 1525)(2275 1475);
WIRE 16 -1 (2025 1575)(2275 1575);
WIRE 16 -1 (2275 1575)(2275 1525);
WIRE 16 -1 (2025 1625)(2275 1625);
WIRE 16 -1 (2275 1575)(2275 1625);
WIRE 16 -1 (2025 1675)(2275 1675);
WIRE 16 -1 (2275 1675)(2275 1625);
WIRE 16 -1 (2025 1725)(2275 1725);
WIRE 16 -1 (2275 1725)(2275 1675);
WIRE 16 -1 (2025 1775)(2275 1775);
WIRE 16 -1 (2275 1775)(2275 1725);
WIRE 16 -1 (2025 1825)(2275 1825);
WIRE 16 -1 (2275 1825)(2275 1775);
WIRE 16 -1 (2025 1875)(2275 1875);
WIRE 16 -1 (2275 1875)(2275 1825);
WIRE 16 -1 (2025 1925)(2275 1925);
WIRE 16 -1 (2275 1925)(2275 1875);
WIRE 16 -1 (2275 1975)(2025 1975);
WIRE 16 -1 (2275 1975)(2275 1925);
WIRE 16 -1 (2275 2025)(2025 2025);
WIRE 16 -1 (2275 2025)(2275 1975);
WIRE 16 -1 (2275 2075)(2025 2075);
WIRE 16 -1 (2275 2075)(2275 2025);
WIRE 16 -1 (2275 2125)(2025 2125);
WIRE 16 -1 (2275 2125)(2275 2075);
WIRE 16 -1 (2275 2175)(2025 2175);
WIRE 16 -1 (2275 2175)(2275 2125);
WIRE 16 -1 (2275 2225)(2025 2225);
WIRE 16 -1 (2275 2225)(2275 2175);
WIRE 16 -1 (2275 2275)(2025 2275);
WIRE 16 -1 (2275 2275)(2275 2225);
WIRE 16 -1 (2275 2325)(2025 2325);
WIRE 16 -1 (2275 2325)(2275 2275);
WIRE 16 -1 (2275 2375)(2025 2375);
WIRE 16 -1 (2275 2375)(2275 2325);
WIRE 16 -1 (2025 2425)(2275 2425);
WIRE 16 -1 (2275 2375)(2275 2425);
WIRE 16 -1 (2275 2475)(2025 2475);
WIRE 16 -1 (2275 2425)(2275 2475);
WIRE 16 -1 (2275 2525)(2025 2525);
WIRE 16 -1 (2275 2525)(2275 2475);
WIRE 16 -1 (2275 2575)(2025 2575);
WIRE 16 -1 (2275 2575)(2275 2525);
WIRE 16 -1 (2275 2625)(2025 2625);
WIRE 16 -1 (2275 2625)(2275 2575);
WIRE 16 -1 (2025 2675)(2275 2675);
WIRE 16 -1 (2275 2675)(2275 2625);
WIRE 16 -1 (2025 2725)(2275 2725);
WIRE 16 -1 (2275 2725)(2275 2675);
WIRE 16 -1 (2025 2775)(2275 2775);
WIRE 16 -1 (2275 2725)(2275 2775);
WIRE 16 -1 (2025 2825)(2275 2825);
WIRE 16 -1 (2275 2825)(2275 2775);
WIRE 16 -1 (2025 2875)(2275 2875);
WIRE 16 -1 (2275 2875)(2275 2825);
WIRE 16 -1 (2025 2925)(2275 2925);
WIRE 16 -1 (2275 2925)(2275 2875);
WIRE 16 -1 (2025 2975)(2275 2975);
WIRE 16 -1 (2275 2975)(2275 2925);
WIRE 16 -1 (2025 3025)(2275 3025);
WIRE 16 -1 (2275 3025)(2275 2975);
WIRE 16 -1 (2025 3075)(2275 3075);
WIRE 16 -1 (2275 3075)(2275 3025);
WIRE 16 -1 (2275 3125)(2025 3125);
WIRE 16 -1 (2275 3125)(2275 3075);
WIRE 16 -1 (2275 3175)(2025 3175);
WIRE 16 -1 (2275 3175)(2275 3125);
WIRE 16 -1 (2275 3225)(2025 3225);
WIRE 16 -1 (2275 3225)(2275 3175);
WIRE 16 -1 (2275 3275)(2025 3275);
WIRE 16 -1 (2275 3275)(2275 3225);
WIRE 16 -1 (2275 3325)(2025 3325);
WIRE 16 -1 (2275 3325)(2275 3275);
WIRE 16 -1 (2275 3375)(2025 3375);
WIRE 16 -1 (2275 3375)(2275 3325);
WIRE 16 -1 (2275 3425)(2025 3425);
WIRE 16 -1 (2275 3425)(2275 3375);
WIRE 16 -1 (2275 3475)(2025 3475);
WIRE 16 -1 (2275 3475)(2275 3425);
WIRE 16 -1 (2275 3525)(2025 3525);
WIRE 16 -1 (2275 3525)(2275 3475);
WIRE 16 -1 (2025 3575)(2275 3575);
WIRE 16 -1 (2275 3525)(2275 3575);
WIRE 16 -1 (2275 3625)(2025 3625);
WIRE 16 -1 (2275 3575)(2275 3625);
WIRE 16 -1 (2275 3675)(2025 3675);
WIRE 16 -1 (2275 3675)(2275 3625);
WIRE 16 -1 (2275 3725)(2025 3725);
WIRE 16 -1 (2275 3725)(2275 3675);
WIRE 16 -1 (2275 3775)(2025 3775);
WIRE 16 -1 (2275 3775)(2275 3725);
WIRE 16 -1 (2400 -125)(2650 -125);
WIRE 16 -1 (2400 -75)(2400 -125);
WIRE 16 -1 (2400 -75)(2650 -75);
WIRE 16 -1 (2400 -25)(2400 -75);
WIRE 16 -1 (2400 -25)(2650 -25);
WIRE 16 -1 (2400 25)(2400 -25);
WIRE 16 -1 (2400 25)(2650 25);
WIRE 16 -1 (2400 75)(2400 25);
WIRE 16 -1 (2650 75)(2400 75);
WIRE 16 -1 (2400 125)(2400 75);
WIRE 16 -1 (2400 125)(2650 125);
WIRE 16 -1 (2400 175)(2400 125);
WIRE 16 -1 (2400 175)(2650 175);
WIRE 16 -1 (2400 225)(2400 175);
WIRE 16 -1 (2400 225)(2650 225);
WIRE 16 -1 (2400 275)(2400 225);
WIRE 16 -1 (2400 275)(2650 275);
WIRE 16 -1 (2400 325)(2400 275);
WIRE 16 -1 (2400 325)(2650 325);
WIRE 16 -1 (2400 375)(2400 325);
WIRE 16 -1 (2400 375)(2650 375);
WIRE 16 -1 (2400 425)(2400 375);
WIRE 16 -1 (2650 425)(2400 425);
WIRE 16 -1 (2400 475)(2400 425);
WIRE 16 -1 (2400 475)(2650 475);
WIRE 16 -1 (2400 525)(2400 475);
WIRE 16 -1 (2400 525)(2650 525);
WIRE 16 -1 (2400 575)(2400 525);
WIRE 16 -1 (2400 575)(2650 575);
WIRE 16 -1 (2400 625)(2400 575);
WIRE 16 -1 (2400 625)(2650 625);
WIRE 16 -1 (2400 675)(2400 625);
WIRE 16 -1 (2400 675)(2650 675);
WIRE 16 -1 (2400 725)(2400 675);
WIRE 16 -1 (2650 725)(2400 725);
WIRE 16 -1 (2400 775)(2400 725);
WIRE 16 -1 (2400 775)(2650 775);
WIRE 16 -1 (2400 825)(2400 775);
WIRE 16 -1 (2400 825)(2650 825);
WIRE 16 -1 (2400 875)(2400 825);
WIRE 16 -1 (2400 875)(2650 875);
WIRE 16 -1 (2400 925)(2400 875);
WIRE 16 -1 (2400 925)(2650 925);
WIRE 16 -1 (2400 975)(2400 925);
WIRE 16 -1 (2400 975)(2650 975);
WIRE 16 -1 (2400 1025)(2400 975);
WIRE 16 -1 (2400 1025)(2650 1025);
WIRE 16 -1 (2400 1075)(2400 1025);
WIRE 16 -1 (2400 1075)(2650 1075);
WIRE 16 -1 (2400 1125)(2400 1075);
WIRE 16 -1 (2400 1125)(2650 1125);
WIRE 16 -1 (2400 1175)(2400 1125);
WIRE 16 -1 (2400 1175)(2650 1175);
WIRE 16 -1 (2400 1225)(2400 1175);
WIRE 16 -1 (2400 1225)(2650 1225);
WIRE 16 -1 (2400 1275)(2400 1225);
WIRE 16 -1 (2400 1275)(2650 1275);
WIRE 16 -1 (2400 1325)(2400 1275);
WIRE 16 -1 (2400 1325)(2650 1325);
WIRE 16 -1 (2400 1375)(2400 1325);
WIRE 16 -1 (2400 1375)(2650 1375);
WIRE 16 -1 (2400 1425)(2400 1375);
WIRE 16 -1 (2400 1425)(2650 1425);
WIRE 16 -1 (2400 1475)(2400 1425);
WIRE 16 -1 (2400 1475)(2650 1475);
WIRE 16 -1 (2400 1525)(2400 1475);
WIRE 16 -1 (2400 1525)(2650 1525);
WIRE 16 -1 (2400 1575)(2400 1525);
WIRE 16 -1 (2400 1575)(2650 1575);
WIRE 16 -1 (2400 1625)(2400 1575);
WIRE 16 -1 (2400 1625)(2650 1625);
WIRE 16 -1 (2400 1675)(2400 1625);
WIRE 16 -1 (2400 1675)(2650 1675);
WIRE 16 -1 (2400 1725)(2400 1675);
WIRE 16 -1 (2650 1725)(2400 1725);
WIRE 16 -1 (2400 1775)(2400 1725);
WIRE 16 -1 (2400 1775)(2650 1775);
WIRE 16 -1 (2400 1825)(2400 1775);
WIRE 16 -1 (2400 1825)(2650 1825);
WIRE 16 -1 (2400 1875)(2400 1825);
WIRE 16 -1 (2400 1875)(2650 1875);
WIRE 16 -1 (2400 1925)(2400 1875);
WIRE 16 -1 (2400 1925)(2650 1925);
WIRE 16 -1 (2400 1975)(2400 1925);
WIRE 16 -1 (2400 1975)(2650 1975);
WIRE 16 -1 (2400 2025)(2400 1975);
WIRE 16 -1 (2400 2025)(2650 2025);
WIRE 16 -1 (2400 2075)(2400 2025);
WIRE 16 -1 (2400 2075)(2650 2075);
WIRE 16 -1 (2400 2125)(2400 2075);
WIRE 16 -1 (2400 2125)(2650 2125);
WIRE 16 -1 (2400 2175)(2400 2125);
WIRE 16 -1 (2400 2175)(2650 2175);
WIRE 16 -1 (2400 2225)(2400 2175);
WIRE 16 -1 (2400 2225)(2650 2225);
WIRE 16 -1 (2400 2275)(2400 2225);
WIRE 16 -1 (2400 2275)(2650 2275);
WIRE 16 -1 (2400 2325)(2400 2275);
WIRE 16 -1 (2400 2325)(2650 2325);
WIRE 16 -1 (2400 2375)(2400 2325);
WIRE 16 -1 (2400 2375)(2650 2375);
WIRE 16 -1 (2400 2425)(2400 2375);
WIRE 16 -1 (2400 2425)(2650 2425);
WIRE 16 -1 (2400 2475)(2400 2425);
WIRE 16 -1 (2400 2475)(2650 2475);
WIRE 16 -1 (2400 2525)(2400 2475);
WIRE 16 -1 (2400 2525)(2650 2525);
WIRE 16 -1 (2400 2575)(2400 2525);
WIRE 16 -1 (2400 2575)(2650 2575);
WIRE 16 -1 (2400 2625)(2400 2575);
WIRE 16 -1 (2400 2625)(2650 2625);
WIRE 16 -1 (2400 2675)(2400 2625);
WIRE 16 -1 (2400 2675)(2650 2675);
WIRE 16 -1 (2400 2725)(2400 2675);
WIRE 16 -1 (2400 2725)(2650 2725);
WIRE 16 -1 (2400 2775)(2400 2725);
WIRE 16 -1 (2400 2775)(2650 2775);
WIRE 16 -1 (2400 2825)(2400 2775);
WIRE 16 -1 (2400 2825)(2650 2825);
WIRE 16 -1 (2400 2875)(2400 2825);
WIRE 16 -1 (2400 2875)(2650 2875);
WIRE 16 -1 (2400 2925)(2400 2875);
WIRE 16 -1 (2400 2925)(2650 2925);
WIRE 16 -1 (2400 2975)(2400 2925);
WIRE 16 -1 (2400 2975)(2650 2975);
WIRE 16 -1 (2400 3025)(2400 2975);
WIRE 16 -1 (2400 3025)(2650 3025);
WIRE 16 -1 (2400 3075)(2400 3025);
WIRE 16 -1 (2400 3075)(2650 3075);
WIRE 16 -1 (2400 3125)(2400 3075);
WIRE 16 -1 (2650 3125)(2400 3125);
WIRE 16 -1 (2400 3175)(2400 3125);
WIRE 16 -1 (2650 3175)(2400 3175);
WIRE 16 -1 (2400 3225)(2400 3175);
WIRE 16 -1 (2650 3225)(2400 3225);
WIRE 16 -1 (2400 3275)(2400 3225);
WIRE 16 -1 (2650 3275)(2400 3275);
WIRE 16 -1 (2400 3325)(2400 3275);
WIRE 16 -1 (2650 3325)(2400 3325);
WIRE 16 -1 (2400 3375)(2400 3325);
WIRE 16 -1 (2650 3375)(2400 3375);
WIRE 16 -1 (2400 3425)(2400 3375);
WIRE 16 -1 (2650 3425)(2400 3425);
WIRE 16 -1 (2400 3475)(2400 3425);
WIRE 16 -1 (2650 3475)(2400 3475);
WIRE 16 -1 (2400 3525)(2400 3475);
WIRE 16 -1 (2650 3525)(2400 3525);
WIRE 16 -1 (2400 3575)(2400 3525);
WIRE 16 -1 (2650 3575)(2400 3575);
WIRE 16 -1 (2400 3625)(2400 3575);
WIRE 16 -1 (2650 3625)(2400 3625);
WIRE 16 -1 (2400 3675)(2400 3625);
WIRE 16 -1 (2650 3675)(2400 3675);
WIRE 16 -1 (2400 3725)(2400 3675);
WIRE 16 -1 (2650 3725)(2400 3725);
WIRE 16 -1 (2400 3775)(2400 3725);
WIRE 16 -1 (2650 3775)(2400 3775);
WIRE 16 -1 (5300 3775)(5050 3775);
WIRE 16 -1 (5300 3725)(5050 3725);
WIRE 16 -1 (5300 3775)(5300 3725);
WIRE 16 -1 (5300 3675)(5050 3675);
WIRE 16 -1 (5300 3725)(5300 3675);
WIRE 16 -1 (5300 3625)(5050 3625);
WIRE 16 -1 (5300 3675)(5300 3625);
WIRE 16 -1 (5050 3575)(5300 3575);
WIRE 16 -1 (5300 3575)(5300 3625);
WIRE 16 -1 (5300 3525)(5050 3525);
WIRE 16 -1 (5300 3525)(5300 3575);
WIRE 16 -1 (5300 3475)(5050 3475);
WIRE 16 -1 (5300 3525)(5300 3475);
WIRE 16 -1 (5300 3425)(5050 3425);
WIRE 16 -1 (5300 3475)(5300 3425);
WIRE 16 -1 (5300 3375)(5050 3375);
WIRE 16 -1 (5300 3425)(5300 3375);
WIRE 16 -1 (5300 3325)(5050 3325);
WIRE 16 -1 (5300 3375)(5300 3325);
WIRE 16 -1 (5300 3275)(5050 3275);
WIRE 16 -1 (5300 3325)(5300 3275);
WIRE 16 -1 (5300 3225)(5050 3225);
WIRE 16 -1 (5300 3275)(5300 3225);
WIRE 16 -1 (5300 3175)(5050 3175);
WIRE 16 -1 (5300 3225)(5300 3175);
WIRE 16 -1 (5300 3125)(5050 3125);
WIRE 16 -1 (5300 3175)(5300 3125);
WIRE 16 -1 (5050 3075)(5300 3075);
WIRE 16 -1 (5300 3125)(5300 3075);
WIRE 16 -1 (5050 3025)(5300 3025);
WIRE 16 -1 (5300 3075)(5300 3025);
WIRE 16 -1 (5050 2975)(5300 2975);
WIRE 16 -1 (5300 3025)(5300 2975);
WIRE 16 -1 (5050 2925)(5300 2925);
WIRE 16 -1 (5300 2975)(5300 2925);
WIRE 16 -1 (5050 2875)(5300 2875);
WIRE 16 -1 (5300 2925)(5300 2875);
WIRE 16 -1 (5050 2825)(5300 2825);
WIRE 16 -1 (5300 2875)(5300 2825);
WIRE 16 -1 (5050 2775)(5300 2775);
WIRE 16 -1 (5300 2825)(5300 2775);
WIRE 16 -1 (5050 2725)(5300 2725);
WIRE 16 -1 (5300 2725)(5300 2775);
WIRE 16 -1 (5050 2675)(5300 2675);
WIRE 16 -1 (5300 2725)(5300 2675);
WIRE 16 -1 (5300 2625)(5050 2625);
WIRE 16 -1 (5300 2675)(5300 2625);
WIRE 16 -1 (5300 2575)(5050 2575);
WIRE 16 -1 (5300 2625)(5300 2575);
WIRE 16 -1 (5300 2525)(5050 2525);
WIRE 16 -1 (5300 2575)(5300 2525);
WIRE 16 -1 (5300 2475)(5050 2475);
WIRE 16 -1 (5300 2525)(5300 2475);
WIRE 16 -1 (5050 2425)(5300 2425);
WIRE 16 -1 (5300 2425)(5300 2475);
WIRE 16 -1 (5300 2375)(5050 2375);
WIRE 16 -1 (5300 2375)(5300 2425);
WIRE 16 -1 (5300 2325)(5050 2325);
WIRE 16 -1 (5300 2375)(5300 2325);
WIRE 16 -1 (5300 2275)(5050 2275);
WIRE 16 -1 (5300 2325)(5300 2275);
WIRE 16 -1 (5300 2225)(5050 2225);
WIRE 16 -1 (5300 2275)(5300 2225);
WIRE 16 -1 (5300 2175)(5050 2175);
WIRE 16 -1 (5300 2225)(5300 2175);
WIRE 16 -1 (5300 2125)(5050 2125);
WIRE 16 -1 (5300 2175)(5300 2125);
WIRE 16 -1 (5300 2075)(5050 2075);
WIRE 16 -1 (5300 2125)(5300 2075);
WIRE 16 -1 (5300 2025)(5050 2025);
WIRE 16 -1 (5300 2075)(5300 2025);
WIRE 16 -1 (5300 1975)(5050 1975);
WIRE 16 -1 (5300 2025)(5300 1975);
WIRE 16 -1 (5050 1925)(5300 1925);
WIRE 16 -1 (5300 1975)(5300 1925);
WIRE 16 -1 (5050 1875)(5300 1875);
WIRE 16 -1 (5300 1925)(5300 1875);
WIRE 16 -1 (5050 1825)(5300 1825);
WIRE 16 -1 (5300 1875)(5300 1825);
WIRE 16 -1 (5050 1775)(5300 1775);
WIRE 16 -1 (5300 1825)(5300 1775);
WIRE 16 -1 (5050 1725)(5300 1725);
WIRE 16 -1 (5300 1775)(5300 1725);
WIRE 16 -1 (5050 1675)(5300 1675);
WIRE 16 -1 (5300 1725)(5300 1675);
WIRE 16 -1 (5050 1625)(5300 1625);
WIRE 16 -1 (5300 1675)(5300 1625);
WIRE 16 -1 (5050 1575)(5300 1575);
WIRE 16 -1 (5300 1575)(5300 1625);
WIRE 16 -1 (5050 1525)(5300 1525);
WIRE 16 -1 (5300 1575)(5300 1525);
WIRE 16 -1 (5300 1475)(5050 1475);
WIRE 16 -1 (5300 1525)(5300 1475);
WIRE 16 -1 (5300 1425)(5050 1425);
WIRE 16 -1 (5300 1475)(5300 1425);
WIRE 16 -1 (5300 1375)(5050 1375);
WIRE 16 -1 (5300 1425)(5300 1375);
WIRE 16 -1 (5300 1325)(5050 1325);
WIRE 16 -1 (5300 1375)(5300 1325);
WIRE 16 -1 (5050 1275)(5300 1275);
WIRE 16 -1 (5300 1275)(5300 1325);
WIRE 16 -1 (5300 1225)(5050 1225);
WIRE 16 -1 (5300 1225)(5300 1275);
WIRE 16 -1 (5300 1175)(5050 1175);
WIRE 16 -1 (5300 1225)(5300 1175);
WIRE 16 -1 (5300 1125)(5050 1125);
WIRE 16 -1 (5300 1175)(5300 1125);
WIRE 16 -1 (5050 1075)(5300 1075);
WIRE 16 -1 (5300 1125)(5300 1075);
WIRE 16 -1 (5050 1025)(5300 1025);
WIRE 16 -1 (5300 1075)(5300 1025);
WIRE 16 -1 (5050 975)(5300 975);
WIRE 16 -1 (5300 1025)(5300 975);
WIRE 16 -1 (5050 925)(5300 925);
WIRE 16 -1 (5300 975)(5300 925);
WIRE 16 -1 (5050 875)(5300 875);
WIRE 16 -1 (5300 925)(5300 875);
WIRE 16 -1 (5050 825)(5300 825);
WIRE 16 -1 (5300 875)(5300 825);
WIRE 16 -1 (5050 775)(5300 775);
WIRE 16 -1 (5300 825)(5300 775);
WIRE 16 -1 (5050 725)(5300 725);
WIRE 16 -1 (5300 725)(5300 775);
WIRE 16 -1 (5050 675)(5300 675);
WIRE 16 -1 (5300 725)(5300 675);
WIRE 16 -1 (5300 625)(5050 625);
WIRE 16 -1 (5300 675)(5300 625);
WIRE 16 -1 (5300 575)(5050 575);
WIRE 16 -1 (5300 625)(5300 575);
WIRE 16 -1 (5300 525)(5050 525);
WIRE 16 -1 (5300 575)(5300 525);
WIRE 16 -1 (5300 475)(5050 475);
WIRE 16 -1 (5300 525)(5300 475);
WIRE 16 -1 (5050 425)(5300 425);
WIRE 16 -1 (5300 425)(5300 475);
WIRE 16 -1 (5300 375)(5050 375);
WIRE 16 -1 (5300 375)(5300 425);
WIRE 16 -1 (5300 325)(5050 325);
WIRE 16 -1 (5300 375)(5300 325);
WIRE 16 -1 (5300 275)(5050 275);
WIRE 16 -1 (5300 325)(5300 275);
WIRE 16 -1 (5050 225)(5300 225);
WIRE 16 -1 (5300 275)(5300 225);
WIRE 16 -1 (5050 175)(5300 175);
WIRE 16 -1 (5300 225)(5300 175);
WIRE 16 -1 (5050 125)(5300 125);
WIRE 16 -1 (5300 175)(5300 125);
WIRE 16 -1 (5050 75)(5300 75);
WIRE 16 -1 (5300 125)(5300 75);
WIRE 16 -1 (5050 25)(5300 25);
WIRE 16 -1 (5300 75)(5300 25);
WIRE 16 -1 (5050 -25)(5300 -25);
WIRE 16 -1 (5300 25)(5300 -25);
WIRE 16 -1 (5050 -75)(5300 -75);
WIRE 16 -1 (5300 -25)(5300 -75);
WIRE 16 -1 (5300 -125)(5300 -75);
WIRE 16 -1 (5050 -125)(5300 -125);
WIRE 16 -1 (-375 3775)(-625 3775);
WIRE 16 -1 (-625 3775)(-625 3725);
WIRE 16 -1 (-375 3725)(-625 3725);
WIRE 16 -1 (-625 3725)(-625 3675);
WIRE 16 -1 (-375 3675)(-625 3675);
WIRE 16 -1 (-625 3675)(-625 3625);
WIRE 16 -1 (-375 3625)(-625 3625);
WIRE 16 -1 (-625 3625)(-625 3575);
WIRE 16 -1 (-375 3575)(-625 3575);
WIRE 16 -1 (-625 3575)(-625 3525);
WIRE 16 -1 (-375 3525)(-625 3525);
WIRE 16 -1 (-625 3525)(-625 3475);
WIRE 16 -1 (-375 3475)(-625 3475);
WIRE 16 -1 (-625 3475)(-625 3425);
WIRE 16 -1 (-375 3425)(-625 3425);
WIRE 16 -1 (-625 3425)(-625 3375);
WIRE 16 -1 (-375 3375)(-625 3375);
WIRE 16 -1 (-625 3375)(-625 3325);
WIRE 16 -1 (-375 3325)(-625 3325);
WIRE 16 -1 (-625 3325)(-625 3275);
WIRE 16 -1 (-375 3275)(-625 3275);
WIRE 16 -1 (-625 3275)(-625 3225);
WIRE 16 -1 (-375 3225)(-625 3225);
WIRE 16 -1 (-625 3225)(-625 3175);
WIRE 16 -1 (-375 3175)(-625 3175);
WIRE 16 -1 (-625 3175)(-625 3125);
WIRE 16 -1 (-375 3125)(-625 3125);
WIRE 16 -1 (-625 3125)(-625 3075);
WIRE 16 -1 (-625 3075)(-375 3075);
WIRE 16 -1 (-625 3025)(-375 3025);
WIRE 16 -1 (-625 3075)(-625 3025);
WIRE 16 -1 (-625 3025)(-625 2975);
WIRE 16 -1 (-625 2975)(-375 2975);
WIRE 16 -1 (-625 2975)(-625 2925);
WIRE 16 -1 (-625 2925)(-375 2925);
WIRE 16 -1 (-625 2925)(-625 2875);
WIRE 16 -1 (-625 2875)(-375 2875);
WIRE 16 -1 (-625 2875)(-625 2825);
WIRE 16 -1 (-625 2825)(-375 2825);
WIRE 16 -1 (-625 2825)(-625 2775);
WIRE 16 -1 (-625 2775)(-375 2775);
WIRE 16 -1 (-625 2775)(-625 2725);
WIRE 16 -1 (-625 2725)(-375 2725);
WIRE 16 -1 (-625 2725)(-625 2675);
WIRE 16 -1 (-625 2675)(-375 2675);
WIRE 16 -1 (-625 2675)(-625 2625);
WIRE 16 -1 (-625 2625)(-375 2625);
WIRE 16 -1 (-625 2625)(-625 2575);
WIRE 16 -1 (-625 2575)(-375 2575);
WIRE 16 -1 (-625 2575)(-625 2525);
WIRE 16 -1 (-625 2525)(-375 2525);
WIRE 16 -1 (-625 2525)(-625 2475);
WIRE 16 -1 (-625 2475)(-375 2475);
WIRE 16 -1 (-625 2475)(-625 2425);
WIRE 16 -1 (-625 2425)(-375 2425);
WIRE 16 -1 (-625 2425)(-625 2375);
WIRE 16 -1 (-625 2375)(-375 2375);
WIRE 16 -1 (-625 2375)(-625 2325);
WIRE 16 -1 (-625 2325)(-375 2325);
WIRE 16 -1 (-625 2325)(-625 2275);
WIRE 16 -1 (-625 2275)(-375 2275);
WIRE 16 -1 (-625 2275)(-625 2225);
WIRE 16 -1 (-625 2225)(-375 2225);
WIRE 16 -1 (-625 2225)(-625 2175);
WIRE 16 -1 (-625 2175)(-375 2175);
WIRE 16 -1 (-625 2175)(-625 2125);
WIRE 16 -1 (-625 2125)(-375 2125);
WIRE 16 -1 (-625 2125)(-625 2075);
WIRE 16 -1 (-625 2075)(-375 2075);
WIRE 16 -1 (-625 2025)(-375 2025);
WIRE 16 -1 (-625 2075)(-625 2025);
WIRE 16 -1 (-625 2025)(-625 1975);
WIRE 16 -1 (-625 1975)(-375 1975);
WIRE 16 -1 (-625 1975)(-625 1925);
WIRE 16 -1 (-625 1925)(-375 1925);
WIRE 16 -1 (-625 1925)(-625 1875);
WIRE 16 -1 (-625 1875)(-375 1875);
WIRE 16 -1 (-625 1875)(-625 1825);
WIRE 16 -1 (-625 1825)(-375 1825);
WIRE 16 -1 (-625 1825)(-625 1775);
WIRE 16 -1 (-625 1775)(-375 1775);
WIRE 16 -1 (-625 1775)(-625 1725);
WIRE 16 -1 (-375 1725)(-625 1725);
WIRE 16 -1 (-625 1725)(-625 1675);
WIRE 16 -1 (-625 1675)(-375 1675);
WIRE 16 -1 (-625 1675)(-625 1625);
WIRE 16 -1 (-625 1625)(-375 1625);
WIRE 16 -1 (-625 1625)(-625 1575);
WIRE 16 -1 (-625 1575)(-375 1575);
WIRE 16 -1 (-625 1575)(-625 1525);
WIRE 16 -1 (-625 1525)(-375 1525);
WIRE 16 -1 (-625 1525)(-625 1475);
WIRE 16 -1 (-625 1475)(-375 1475);
WIRE 16 -1 (-625 1475)(-625 1425);
WIRE 16 -1 (-625 1425)(-375 1425);
WIRE 16 -1 (-625 1425)(-625 1375);
WIRE 16 -1 (-625 1375)(-375 1375);
WIRE 16 -1 (-625 1375)(-625 1325);
WIRE 16 -1 (-625 1325)(-375 1325);
WIRE 16 -1 (-625 1325)(-625 1275);
WIRE 16 -1 (-625 1275)(-375 1275);
WIRE 16 -1 (-625 1275)(-625 1225);
WIRE 16 -1 (-625 1225)(-375 1225);
WIRE 16 -1 (-625 1225)(-625 1175);
WIRE 16 -1 (-625 1175)(-375 1175);
WIRE 16 -1 (-625 1175)(-625 1125);
WIRE 16 -1 (-625 1125)(-375 1125);
WIRE 16 -1 (-625 1125)(-625 1075);
WIRE 16 -1 (-625 1075)(-375 1075);
WIRE 16 -1 (-625 1075)(-625 1025);
WIRE 16 -1 (-625 1025)(-375 1025);
WIRE 16 -1 (-625 975)(-375 975);
WIRE 16 -1 (-625 1025)(-625 975);
WIRE 16 -1 (-625 975)(-625 925);
WIRE 16 -1 (-625 925)(-375 925);
WIRE 16 -1 (-625 925)(-625 875);
WIRE 16 -1 (-625 875)(-375 875);
WIRE 16 -1 (-625 875)(-625 825);
WIRE 16 -1 (-625 825)(-375 825);
WIRE 16 -1 (-625 825)(-625 775);
WIRE 16 -1 (-625 775)(-375 775);
WIRE 16 -1 (-625 775)(-625 725);
WIRE 16 -1 (-375 725)(-625 725);
WIRE 16 -1 (-625 725)(-625 675);
WIRE 16 -1 (-625 675)(-375 675);
WIRE 16 -1 (-625 675)(-625 625);
WIRE 16 -1 (-625 625)(-375 625);
WIRE 16 -1 (-625 625)(-625 575);
WIRE 16 -1 (-625 575)(-375 575);
WIRE 16 -1 (-625 575)(-625 525);
WIRE 16 -1 (-625 525)(-375 525);
WIRE 16 -1 (-625 525)(-625 475);
WIRE 16 -1 (-625 475)(-375 475);
WIRE 16 -1 (-625 475)(-625 425);
WIRE 16 -1 (-375 425)(-625 425);
WIRE 16 -1 (-625 425)(-625 375);
WIRE 16 -1 (-625 375)(-375 375);
WIRE 16 -1 (-625 375)(-625 325);
WIRE 16 -1 (-625 325)(-375 325);
WIRE 16 -1 (-625 325)(-625 275);
WIRE 16 -1 (-625 275)(-375 275);
WIRE 16 -1 (-625 275)(-625 225);
WIRE 16 -1 (-625 225)(-375 225);
WIRE 16 -1 (-625 225)(-625 175);
WIRE 16 -1 (-625 175)(-375 175);
WIRE 16 -1 (-625 175)(-625 125);
WIRE 16 -1 (-625 125)(-375 125);
WIRE 16 -1 (-625 125)(-625 75);
WIRE 16 -1 (-375 75)(-625 75);
WIRE 16 -1 (-625 75)(-625 25);
WIRE 16 -1 (-625 25)(-375 25);
WIRE 16 -1 (-625 -25)(-375 -25);
WIRE 16 -1 (-625 25)(-625 -25);
WIRE 16 -1 (-625 -25)(-625 -75);
WIRE 16 -1 (-625 -75)(-375 -75);
WIRE 16 -1 (-625 -75)(-625 -125);
WIRE 16 -1 (-625 -125)(-375 -125);
WIRE 16 -1 (-3425 3775)(-3675 3775);
WIRE 16 -1 (-3675 3775)(-3675 3725);
WIRE 16 -1 (-3425 3725)(-3675 3725);
WIRE 16 -1 (-3675 3725)(-3675 3675);
WIRE 16 -1 (-3425 3675)(-3675 3675);
WIRE 16 -1 (-3675 3675)(-3675 3625);
WIRE 16 -1 (-3425 3625)(-3675 3625);
WIRE 16 -1 (-3675 3625)(-3675 3575);
WIRE 16 -1 (-3425 3575)(-3675 3575);
WIRE 16 -1 (-3675 3575)(-3675 3525);
WIRE 16 -1 (-3425 3525)(-3675 3525);
WIRE 16 -1 (-3675 3525)(-3675 3475);
WIRE 16 -1 (-3425 3475)(-3675 3475);
WIRE 16 -1 (-3675 3475)(-3675 3425);
WIRE 16 -1 (-3425 3425)(-3675 3425);
WIRE 16 -1 (-3675 3425)(-3675 3375);
WIRE 16 -1 (-3425 3375)(-3675 3375);
WIRE 16 -1 (-3675 3375)(-3675 3325);
WIRE 16 -1 (-3425 3325)(-3675 3325);
WIRE 16 -1 (-3675 3325)(-3675 3275);
WIRE 16 -1 (-3425 3275)(-3675 3275);
WIRE 16 -1 (-3675 3275)(-3675 3225);
WIRE 16 -1 (-3425 3225)(-3675 3225);
WIRE 16 -1 (-3675 3225)(-3675 3175);
WIRE 16 -1 (-3425 3175)(-3675 3175);
WIRE 16 -1 (-3675 3175)(-3675 3125);
WIRE 16 -1 (-3425 3125)(-3675 3125);
WIRE 16 -1 (-3675 3125)(-3675 3075);
WIRE 16 -1 (-3675 3075)(-3425 3075);
WIRE 16 -1 (-3675 3025)(-3425 3025);
WIRE 16 -1 (-3675 3075)(-3675 3025);
WIRE 16 -1 (-3675 3025)(-3675 2975);
WIRE 16 -1 (-3675 2975)(-3425 2975);
WIRE 16 -1 (-3675 2975)(-3675 2925);
WIRE 16 -1 (-3675 2925)(-3425 2925);
WIRE 16 -1 (-3675 2925)(-3675 2875);
WIRE 16 -1 (-3675 2875)(-3425 2875);
WIRE 16 -1 (-3675 2875)(-3675 2825);
WIRE 16 -1 (-3675 2825)(-3425 2825);
WIRE 16 -1 (-3675 2825)(-3675 2775);
WIRE 16 -1 (-3675 2775)(-3425 2775);
WIRE 16 -1 (-3675 2775)(-3675 2725);
WIRE 16 -1 (-3675 2725)(-3425 2725);
WIRE 16 -1 (-3675 2725)(-3675 2675);
WIRE 16 -1 (-3675 2675)(-3425 2675);
WIRE 16 -1 (-3675 2675)(-3675 2625);
WIRE 16 -1 (-3675 2625)(-3425 2625);
WIRE 16 -1 (-3675 2625)(-3675 2575);
WIRE 16 -1 (-3675 2575)(-3425 2575);
WIRE 16 -1 (-3675 2575)(-3675 2525);
WIRE 16 -1 (-3675 2525)(-3425 2525);
WIRE 16 -1 (-3675 2525)(-3675 2475);
WIRE 16 -1 (-3675 2475)(-3425 2475);
WIRE 16 -1 (-3675 2475)(-3675 2425);
WIRE 16 -1 (-3675 2425)(-3425 2425);
WIRE 16 -1 (-3675 2425)(-3675 2375);
WIRE 16 -1 (-3675 2375)(-3425 2375);
WIRE 16 -1 (-3675 2375)(-3675 2325);
WIRE 16 -1 (-3675 2325)(-3425 2325);
WIRE 16 -1 (-3675 2325)(-3675 2275);
WIRE 16 -1 (-3675 2275)(-3425 2275);
WIRE 16 -1 (-3675 2275)(-3675 2225);
WIRE 16 -1 (-3675 2225)(-3425 2225);
WIRE 16 -1 (-3675 2225)(-3675 2175);
WIRE 16 -1 (-3675 2175)(-3425 2175);
WIRE 16 -1 (-3675 2175)(-3675 2125);
WIRE 16 -1 (-3675 2125)(-3425 2125);
WIRE 16 -1 (-3675 2125)(-3675 2075);
WIRE 16 -1 (-3675 2075)(-3425 2075);
WIRE 16 -1 (-3675 2025)(-3425 2025);
WIRE 16 -1 (-3675 2075)(-3675 2025);
WIRE 16 -1 (-3675 2025)(-3675 1975);
WIRE 16 -1 (-3675 1975)(-3425 1975);
WIRE 16 -1 (-3675 1975)(-3675 1925);
WIRE 16 -1 (-3675 1925)(-3425 1925);
WIRE 16 -1 (-3675 1925)(-3675 1875);
WIRE 16 -1 (-3675 1875)(-3425 1875);
WIRE 16 -1 (-3675 1875)(-3675 1825);
WIRE 16 -1 (-3675 1825)(-3425 1825);
WIRE 16 -1 (-3675 1825)(-3675 1775);
WIRE 16 -1 (-3675 1775)(-3425 1775);
WIRE 16 -1 (-3675 1775)(-3675 1725);
WIRE 16 -1 (-3425 1725)(-3675 1725);
WIRE 16 -1 (-3675 1725)(-3675 1675);
WIRE 16 -1 (-3675 1675)(-3425 1675);
WIRE 16 -1 (-3675 1675)(-3675 1625);
WIRE 16 -1 (-3675 1625)(-3425 1625);
WIRE 16 -1 (-3675 1625)(-3675 1575);
WIRE 16 -1 (-3675 1575)(-3425 1575);
WIRE 16 -1 (-3675 1575)(-3675 1525);
WIRE 16 -1 (-3675 1525)(-3425 1525);
WIRE 16 -1 (-3675 1525)(-3675 1475);
WIRE 16 -1 (-3675 1475)(-3425 1475);
WIRE 16 -1 (-3675 1475)(-3675 1425);
WIRE 16 -1 (-3675 1425)(-3425 1425);
WIRE 16 -1 (-3675 1425)(-3675 1375);
WIRE 16 -1 (-3675 1375)(-3425 1375);
WIRE 16 -1 (-3675 1375)(-3675 1325);
WIRE 16 -1 (-3675 1325)(-3425 1325);
WIRE 16 -1 (-3675 1325)(-3675 1275);
WIRE 16 -1 (-3675 1275)(-3425 1275);
WIRE 16 -1 (-3675 1275)(-3675 1225);
WIRE 16 -1 (-3675 1225)(-3425 1225);
WIRE 16 -1 (-3675 1225)(-3675 1175);
WIRE 16 -1 (-3675 1175)(-3425 1175);
WIRE 16 -1 (-3675 1175)(-3675 1125);
WIRE 16 -1 (-3675 1125)(-3425 1125);
WIRE 16 -1 (-3675 1125)(-3675 1075);
WIRE 16 -1 (-3675 1075)(-3425 1075);
WIRE 16 -1 (-3675 1075)(-3675 1025);
WIRE 16 -1 (-3675 1025)(-3425 1025);
WIRE 16 -1 (-3675 975)(-3425 975);
WIRE 16 -1 (-3675 1025)(-3675 975);
WIRE 16 -1 (-3675 975)(-3675 925);
WIRE 16 -1 (-3675 925)(-3425 925);
WIRE 16 -1 (-3675 925)(-3675 875);
WIRE 16 -1 (-3675 875)(-3425 875);
WIRE 16 -1 (-3675 875)(-3675 825);
WIRE 16 -1 (-3675 825)(-3425 825);
WIRE 16 -1 (-3675 825)(-3675 775);
WIRE 16 -1 (-3675 775)(-3425 775);
WIRE 16 -1 (-3675 775)(-3675 725);
WIRE 16 -1 (-3425 725)(-3675 725);
WIRE 16 -1 (-3675 725)(-3675 675);
WIRE 16 -1 (-3675 675)(-3425 675);
WIRE 16 -1 (-3675 675)(-3675 625);
WIRE 16 -1 (-3675 625)(-3425 625);
WIRE 16 -1 (-3675 625)(-3675 575);
WIRE 16 -1 (-3675 575)(-3425 575);
WIRE 16 -1 (-3675 575)(-3675 525);
WIRE 16 -1 (-3675 525)(-3425 525);
WIRE 16 -1 (-3675 525)(-3675 475);
WIRE 16 -1 (-3675 475)(-3425 475);
WIRE 16 -1 (-3675 475)(-3675 425);
WIRE 16 -1 (-3425 425)(-3675 425);
WIRE 16 -1 (-3675 425)(-3675 375);
WIRE 16 -1 (-3675 375)(-3425 375);
WIRE 16 -1 (-3675 375)(-3675 325);
WIRE 16 -1 (-3675 325)(-3425 325);
WIRE 16 -1 (-3675 325)(-3675 275);
WIRE 16 -1 (-3675 275)(-3425 275);
WIRE 16 -1 (-3675 275)(-3675 225);
WIRE 16 -1 (-3675 225)(-3425 225);
WIRE 16 -1 (-3675 225)(-3675 175);
WIRE 16 -1 (-3675 175)(-3425 175);
WIRE 16 -1 (-3675 175)(-3675 125);
WIRE 16 -1 (-3675 125)(-3425 125);
WIRE 16 -1 (-3675 125)(-3675 75);
WIRE 16 -1 (-3425 75)(-3675 75);
WIRE 16 -1 (-3675 75)(-3675 25);
WIRE 16 -1 (-3675 25)(-3425 25);
WIRE 16 -1 (-3675 -25)(-3425 -25);
WIRE 16 -1 (-3675 25)(-3675 -25);
WIRE 16 -1 (-3675 -25)(-3675 -75);
WIRE 16 -1 (-3675 -75)(-3425 -75);
WIRE 16 -1 (-3675 -75)(-3675 -125);
WIRE 16 -1 (-3675 -125)(-3425 -125);
WIRE 16 -1 (-775 3775)(-1025 3775);
WIRE 16 -1 (-775 3725)(-1025 3725);
WIRE 16 -1 (-775 3775)(-775 3725);
WIRE 16 -1 (-775 3675)(-1025 3675);
WIRE 16 -1 (-775 3725)(-775 3675);
WIRE 16 -1 (-775 3625)(-1025 3625);
WIRE 16 -1 (-775 3675)(-775 3625);
WIRE 16 -1 (-1025 3575)(-775 3575);
WIRE 16 -1 (-775 3575)(-775 3625);
WIRE 16 -1 (-775 3525)(-1025 3525);
WIRE 16 -1 (-775 3525)(-775 3575);
WIRE 16 -1 (-775 3475)(-1025 3475);
WIRE 16 -1 (-775 3525)(-775 3475);
WIRE 16 -1 (-775 3425)(-1025 3425);
WIRE 16 -1 (-775 3475)(-775 3425);
WIRE 16 -1 (-775 3375)(-1025 3375);
WIRE 16 -1 (-775 3425)(-775 3375);
WIRE 16 -1 (-775 3325)(-1025 3325);
WIRE 16 -1 (-775 3375)(-775 3325);
WIRE 16 -1 (-775 3275)(-1025 3275);
WIRE 16 -1 (-775 3325)(-775 3275);
WIRE 16 -1 (-775 3225)(-1025 3225);
WIRE 16 -1 (-775 3275)(-775 3225);
WIRE 16 -1 (-775 3175)(-1025 3175);
WIRE 16 -1 (-775 3225)(-775 3175);
WIRE 16 -1 (-775 3125)(-1025 3125);
WIRE 16 -1 (-775 3175)(-775 3125);
WIRE 16 -1 (-1025 3075)(-775 3075);
WIRE 16 -1 (-775 3125)(-775 3075);
WIRE 16 -1 (-1025 3025)(-775 3025);
WIRE 16 -1 (-775 3075)(-775 3025);
WIRE 16 -1 (-1025 2975)(-775 2975);
WIRE 16 -1 (-775 3025)(-775 2975);
WIRE 16 -1 (-1025 2925)(-775 2925);
WIRE 16 -1 (-775 2975)(-775 2925);
WIRE 16 -1 (-1025 2875)(-775 2875);
WIRE 16 -1 (-775 2925)(-775 2875);
WIRE 16 -1 (-1025 2825)(-775 2825);
WIRE 16 -1 (-775 2875)(-775 2825);
WIRE 16 -1 (-1025 2775)(-775 2775);
WIRE 16 -1 (-775 2825)(-775 2775);
WIRE 16 -1 (-1025 2725)(-775 2725);
WIRE 16 -1 (-775 2725)(-775 2775);
WIRE 16 -1 (-1025 2675)(-775 2675);
WIRE 16 -1 (-775 2725)(-775 2675);
WIRE 16 -1 (-775 2625)(-1025 2625);
WIRE 16 -1 (-775 2675)(-775 2625);
WIRE 16 -1 (-775 2575)(-1025 2575);
WIRE 16 -1 (-775 2625)(-775 2575);
WIRE 16 -1 (-775 2525)(-1025 2525);
WIRE 16 -1 (-775 2575)(-775 2525);
WIRE 16 -1 (-775 2475)(-1025 2475);
WIRE 16 -1 (-775 2525)(-775 2475);
WIRE 16 -1 (-1025 2425)(-775 2425);
WIRE 16 -1 (-775 2425)(-775 2475);
WIRE 16 -1 (-775 2375)(-1025 2375);
WIRE 16 -1 (-775 2375)(-775 2425);
WIRE 16 -1 (-775 2325)(-1025 2325);
WIRE 16 -1 (-775 2375)(-775 2325);
WIRE 16 -1 (-775 2275)(-1025 2275);
WIRE 16 -1 (-775 2325)(-775 2275);
WIRE 16 -1 (-775 2225)(-1025 2225);
WIRE 16 -1 (-775 2275)(-775 2225);
WIRE 16 -1 (-775 2175)(-1025 2175);
WIRE 16 -1 (-775 2225)(-775 2175);
WIRE 16 -1 (-775 2125)(-1025 2125);
WIRE 16 -1 (-775 2175)(-775 2125);
WIRE 16 -1 (-775 2075)(-1025 2075);
WIRE 16 -1 (-775 2125)(-775 2075);
WIRE 16 -1 (-775 2025)(-1025 2025);
WIRE 16 -1 (-775 2075)(-775 2025);
WIRE 16 -1 (-775 1975)(-1025 1975);
WIRE 16 -1 (-775 2025)(-775 1975);
WIRE 16 -1 (-1025 1925)(-775 1925);
WIRE 16 -1 (-775 1975)(-775 1925);
WIRE 16 -1 (-1025 1875)(-775 1875);
WIRE 16 -1 (-775 1925)(-775 1875);
WIRE 16 -1 (-1025 1825)(-775 1825);
WIRE 16 -1 (-775 1875)(-775 1825);
WIRE 16 -1 (-1025 1775)(-775 1775);
WIRE 16 -1 (-775 1825)(-775 1775);
WIRE 16 -1 (-1025 1725)(-775 1725);
WIRE 16 -1 (-775 1775)(-775 1725);
WIRE 16 -1 (-1025 1675)(-775 1675);
WIRE 16 -1 (-775 1725)(-775 1675);
WIRE 16 -1 (-1025 1625)(-775 1625);
WIRE 16 -1 (-775 1675)(-775 1625);
WIRE 16 -1 (-1025 1575)(-775 1575);
WIRE 16 -1 (-775 1575)(-775 1625);
WIRE 16 -1 (-1025 1525)(-775 1525);
WIRE 16 -1 (-775 1575)(-775 1525);
WIRE 16 -1 (-775 1475)(-1025 1475);
WIRE 16 -1 (-775 1525)(-775 1475);
WIRE 16 -1 (-775 1425)(-1025 1425);
WIRE 16 -1 (-775 1475)(-775 1425);
WIRE 16 -1 (-775 1375)(-1025 1375);
WIRE 16 -1 (-775 1425)(-775 1375);
WIRE 16 -1 (-775 1325)(-1025 1325);
WIRE 16 -1 (-775 1375)(-775 1325);
WIRE 16 -1 (-1025 1275)(-775 1275);
WIRE 16 -1 (-775 1275)(-775 1325);
WIRE 16 -1 (-775 1225)(-1025 1225);
WIRE 16 -1 (-775 1225)(-775 1275);
WIRE 16 -1 (-775 1175)(-1025 1175);
WIRE 16 -1 (-775 1225)(-775 1175);
WIRE 16 -1 (-775 1125)(-1025 1125);
WIRE 16 -1 (-775 1175)(-775 1125);
WIRE 16 -1 (-1025 1075)(-775 1075);
WIRE 16 -1 (-775 1125)(-775 1075);
WIRE 16 -1 (-1025 1025)(-775 1025);
WIRE 16 -1 (-775 1075)(-775 1025);
WIRE 16 -1 (-1025 975)(-775 975);
WIRE 16 -1 (-775 1025)(-775 975);
WIRE 16 -1 (-1025 925)(-775 925);
WIRE 16 -1 (-775 975)(-775 925);
WIRE 16 -1 (-1025 875)(-775 875);
WIRE 16 -1 (-775 925)(-775 875);
WIRE 16 -1 (-1025 825)(-775 825);
WIRE 16 -1 (-775 875)(-775 825);
WIRE 16 -1 (-1025 775)(-775 775);
WIRE 16 -1 (-775 825)(-775 775);
WIRE 16 -1 (-1025 725)(-775 725);
WIRE 16 -1 (-775 725)(-775 775);
WIRE 16 -1 (-1025 675)(-775 675);
WIRE 16 -1 (-775 725)(-775 675);
WIRE 16 -1 (-775 625)(-1025 625);
WIRE 16 -1 (-775 675)(-775 625);
WIRE 16 -1 (-775 575)(-1025 575);
WIRE 16 -1 (-775 625)(-775 575);
WIRE 16 -1 (-775 525)(-1025 525);
WIRE 16 -1 (-775 575)(-775 525);
WIRE 16 -1 (-775 475)(-1025 475);
WIRE 16 -1 (-775 525)(-775 475);
WIRE 16 -1 (-1025 425)(-775 425);
WIRE 16 -1 (-775 425)(-775 475);
WIRE 16 -1 (-775 375)(-1025 375);
WIRE 16 -1 (-775 375)(-775 425);
WIRE 16 -1 (-775 325)(-1025 325);
WIRE 16 -1 (-775 375)(-775 325);
WIRE 16 -1 (-775 275)(-1025 275);
WIRE 16 -1 (-775 325)(-775 275);
WIRE 16 -1 (-1025 225)(-775 225);
WIRE 16 -1 (-775 275)(-775 225);
WIRE 16 -1 (-1025 175)(-775 175);
WIRE 16 -1 (-775 225)(-775 175);
WIRE 16 -1 (-1025 125)(-775 125);
WIRE 16 -1 (-775 175)(-775 125);
WIRE 16 -1 (-1025 75)(-775 75);
WIRE 16 -1 (-775 125)(-775 75);
WIRE 16 -1 (-1025 25)(-775 25);
WIRE 16 -1 (-775 75)(-775 25);
WIRE 16 -1 (-1025 -25)(-775 -25);
WIRE 16 -1 (-775 25)(-775 -25);
WIRE 16 -1 (-1025 -75)(-775 -75);
WIRE 16 -1 (-775 -25)(-775 -75);
WIRE 16 -1 (-775 -125)(-775 -75);
WIRE 16 -1 (-1025 -125)(-775 -125);
DOT 1 (5300 3725);
DOT 1 (5300 3675);
DOT 1 (5300 3625);
DOT 1 (5300 3575);
DOT 1 (5300 3525);
DOT 1 (5300 3475);
DOT 1 (5300 3425);
DOT 1 (5300 3375);
DOT 1 (5300 3275);
DOT 1 (5300 3225);
DOT 1 (5300 3325);
DOT 1 (5300 3125);
DOT 1 (5300 3175);
DOT 1 (5300 3075);
DOT 1 (5300 2975);
DOT 1 (5300 3025);
DOT 1 (5300 2875);
DOT 1 (5300 2925);
DOT 1 (5300 2825);
DOT 1 (5300 2775);
DOT 1 (5300 2725);
DOT 1 (5300 2625);
DOT 1 (5300 2575);
DOT 1 (5300 2675);
DOT 1 (5300 2475);
DOT 1 (5300 2525);
DOT 1 (5300 2325);
DOT 1 (5300 2375);
DOT 1 (5300 2425);
DOT 1 (5300 2225);
DOT 1 (5300 2275);
DOT 1 (5300 2075);
DOT 1 (5300 2125);
DOT 1 (5300 2175);
DOT 1 (5300 2025);
DOT 1 (5300 1975);
DOT 1 (5300 1925);
DOT 1 (5300 1875);
DOT 1 (5300 1825);
DOT 1 (5300 1775);
DOT 1 (5300 1725);
DOT 1 (5300 1675);
DOT 1 (5300 1575);
DOT 1 (5300 1625);
DOT 1 (5300 1525);
DOT 1 (5300 1475);
DOT 1 (5300 1425);
DOT 1 (5300 1375);
DOT 1 (5300 1325);
DOT 1 (5300 1275);
DOT 1 (5300 1175);
DOT 1 (5300 1225);
DOT 1 (5300 1075);
DOT 1 (5300 1125);
DOT 1 (5300 1025);
DOT 1 (5300 975);
DOT 1 (5300 925);
DOT 1 (5300 825);
DOT 1 (5300 875);
DOT 1 (5300 775);
DOT 1 (5300 675);
DOT 1 (5300 725);
DOT 1 (5300 575);
DOT 1 (5300 625);
DOT 1 (5300 525);
DOT 1 (5300 475);
DOT 1 (5300 425);
DOT 1 (5300 325);
DOT 1 (5300 375);
DOT 1 (5300 275);
DOT 1 (5300 225);
DOT 1 (5300 175);
DOT 1 (5300 25);
DOT 1 (5300 75);
DOT 1 (5300 125);
DOT 1 (2400 3725);
DOT 1 (2400 3625);
DOT 1 (2400 3675);
DOT 1 (2275 3675);
DOT 1 (2275 3625);
DOT 1 (2400 3575);
DOT 1 (2400 3475);
DOT 1 (2400 3425);
DOT 1 (2400 3375);
DOT 1 (2400 3325);
DOT 1 (2400 3275);
DOT 1 (2400 3225);
DOT 1 (2400 3175);
DOT 1 (2400 3125);
DOT 1 (2275 3575);
DOT 1 (2275 3525);
DOT 1 (2275 3475);
DOT 1 (2275 3425);
DOT 1 (2275 3375);
DOT 1 (2275 3325);
DOT 1 (2275 3275);
DOT 1 (2275 3225);
DOT 1 (2275 3175);
DOT 1 (2275 3125);
DOT 1 (2400 3075);
DOT 1 (2275 3075);
DOT 1 (2400 3025);
DOT 1 (2400 2975);
DOT 1 (2400 2925);
DOT 1 (2400 2875);
DOT 1 (2400 2825);
DOT 1 (2400 2775);
DOT 1 (2400 2725);
DOT 1 (2400 2675);
DOT 1 (2400 2625);
DOT 1 (2400 2575);
DOT 1 (2275 3025);
DOT 1 (2275 2975);
DOT 1 (2275 2925);
DOT 1 (2275 2875);
DOT 1 (2275 2825);
DOT 1 (2275 2725);
DOT 1 (2275 2775);
DOT 1 (2275 2675);
DOT 1 (2275 2625);
DOT 1 (2275 2575);
DOT 1 (2400 2525);
DOT 1 (2400 2475);
DOT 1 (2400 2425);
DOT 1 (2400 2375);
DOT 1 (2400 2325);
DOT 1 (2400 2275);
DOT 1 (2400 2225);
DOT 1 (2400 2175);
DOT 1 (2400 2125);
DOT 1 (2400 2075);
DOT 1 (2275 2525);
DOT 1 (2275 2475);
DOT 1 (2275 2425);
DOT 1 (2275 2375);
DOT 1 (2275 2325);
DOT 1 (2275 2275);
DOT 1 (2275 2225);
DOT 1 (2275 2175);
DOT 1 (2275 2125);
DOT 1 (2275 2075);
DOT 1 (2400 2025);
DOT 1 (2400 1975);
DOT 1 (2400 1925);
DOT 1 (2400 1875);
DOT 1 (2400 1825);
DOT 1 (2400 1775);
DOT 1 (2400 1725);
DOT 1 (2400 1675);
DOT 1 (2400 1575);
DOT 1 (2400 1625);
DOT 1 (2275 2025);
DOT 1 (2275 1975);
DOT 1 (2275 1925);
DOT 1 (2275 1875);
DOT 1 (2275 1825);
DOT 1 (2275 1775);
DOT 1 (2275 1675);
DOT 1 (2275 1575);
DOT 1 (2275 1625);
DOT 1 (2400 1525);
DOT 1 (2400 1475);
DOT 1 (2400 1425);
DOT 1 (2400 1325);
DOT 1 (2400 1375);
DOT 1 (2400 1225);
DOT 1 (2400 1175);
DOT 1 (2400 1125);
DOT 1 (2400 1075);
DOT 1 (2275 1525);
DOT 1 (2275 1475);
DOT 1 (2275 1425);
DOT 1 (2275 1375);
DOT 1 (2275 1275);
DOT 1 (2275 1225);
DOT 1 (2275 1175);
DOT 1 (2275 1125);
DOT 1 (2275 1075);
DOT 1 (2400 1025);
DOT 1 (2275 1025);
DOT 1 (2400 975);
DOT 1 (2400 925);
DOT 1 (2400 875);
DOT 1 (2400 825);
DOT 1 (2400 775);
DOT 1 (2400 725);
DOT 1 (2400 675);
DOT 1 (2400 625);
DOT 1 (2400 575);
DOT 1 (2275 975);
DOT 1 (2275 925);
DOT 1 (2275 875);
DOT 1 (2275 825);
DOT 1 (2275 775);
DOT 1 (2275 675);
DOT 1 (2275 725);
DOT 1 (2275 625);
DOT 1 (2275 575);
DOT 1 (2400 525);
DOT 1 (2275 525);
DOT 1 (2400 475);
DOT 1 (2400 425);
DOT 1 (2400 375);
DOT 1 (2400 325);
DOT 1 (2400 275);
DOT 1 (2400 175);
DOT 1 (2400 225);
DOT 1 (2400 125);
DOT 1 (2400 75);
DOT 1 (2400 25);
DOT 1 (2275 475);
DOT 1 (2275 425);
DOT 1 (2275 375);
DOT 1 (2275 325);
DOT 1 (2275 275);
DOT 1 (2275 175);
DOT 1 (2275 225);
DOT 1 (2275 125);
DOT 1 (2275 75);
DOT 1 (2275 25);
DOT 1 (5300 -25);
DOT 1 (5300 -75);
DOT 1 (5300 -125);
DOT 1 (5300 -175);
DOT 1 (2400 -25);
DOT 1 (2400 -75);
DOT 1 (2400 -125);
DOT 1 (2400 -175);
DOT 1 (2275 -25);
DOT 1 (2275 -75);
DOT 1 (2275 -125);
DOT 1 (2275 -175);
DOT 1 (-625 3725);
DOT 1 (-625 3625);
DOT 1 (-625 3675);
DOT 1 (-775 3725);
DOT 1 (-775 3625);
DOT 1 (-775 3675);
DOT 1 (-625 3575);
DOT 1 (-625 3525);
DOT 1 (-625 3475);
DOT 1 (-625 3425);
DOT 1 (-625 3375);
DOT 1 (-625 3325);
DOT 1 (-625 3275);
DOT 1 (-625 3225);
DOT 1 (-625 3175);
DOT 1 (-625 3125);
DOT 1 (-775 3525);
DOT 1 (-775 3475);
DOT 1 (-775 3575);
DOT 1 (-775 3425);
DOT 1 (-775 3375);
DOT 1 (-775 3225);
DOT 1 (-775 3325);
DOT 1 (-775 3275);
DOT 1 (-775 3175);
DOT 1 (-775 3125);
DOT 1 (-625 3075);
DOT 1 (-775 3075);
DOT 1 (-625 2975);
DOT 1 (-625 3025);
DOT 1 (-625 2925);
DOT 1 (-625 2875);
DOT 1 (-625 2825);
DOT 1 (-625 2725);
DOT 1 (-625 2775);
DOT 1 (-625 2675);
DOT 1 (-625 2625);
DOT 1 (-625 2575);
DOT 1 (-775 2975);
DOT 1 (-775 3025);
DOT 1 (-775 2925);
DOT 1 (-775 2875);
DOT 1 (-775 2825);
DOT 1 (-775 2725);
DOT 1 (-775 2775);
DOT 1 (-775 2675);
DOT 1 (-775 2625);
DOT 1 (-775 2575);
DOT 1 (-625 2475);
DOT 1 (-625 2525);
DOT 1 (-625 2425);
DOT 1 (-625 2375);
DOT 1 (-625 2325);
DOT 1 (-625 2275);
DOT 1 (-625 2225);
DOT 1 (-625 2175);
DOT 1 (-625 2125);
DOT 1 (-625 2075);
DOT 1 (-775 2475);
DOT 1 (-775 2525);
DOT 1 (-775 2425);
DOT 1 (-775 2375);
DOT 1 (-775 2325);
DOT 1 (-775 2225);
DOT 1 (-775 2275);
DOT 1 (-775 2175);
DOT 1 (-775 2125);
DOT 1 (-775 2075);
DOT 1 (-625 2025);
DOT 1 (-625 1975);
DOT 1 (-625 1925);
DOT 1 (-625 1775);
DOT 1 (-625 1675);
DOT 1 (-625 1575);
DOT 1 (-625 1625);
DOT 1 (-775 1975);
DOT 1 (-775 2025);
DOT 1 (-775 1925);
DOT 1 (-775 1875);
DOT 1 (-775 1825);
DOT 1 (-775 1775);
DOT 1 (-775 1625);
DOT 1 (-775 1575);
DOT 1 (-625 1525);
DOT 1 (-625 1475);
DOT 1 (-625 1425);
DOT 1 (-625 1375);
DOT 1 (-625 1325);
DOT 1 (-625 1275);
DOT 1 (-625 1225);
DOT 1 (-625 1175);
DOT 1 (-625 1125);
DOT 1 (-625 1075);
DOT 1 (-775 1475);
DOT 1 (-775 1425);
DOT 1 (-775 1525);
DOT 1 (-775 1375);
DOT 1 (-775 1325);
DOT 1 (-775 1175);
DOT 1 (-775 1225);
DOT 1 (-775 1275);
DOT 1 (-775 1125);
DOT 1 (-775 1075);
DOT 1 (-625 1025);
DOT 1 (-775 1025);
DOT 1 (-625 925);
DOT 1 (-625 975);
DOT 1 (-625 875);
DOT 1 (-625 825);
DOT 1 (-625 775);
DOT 1 (-625 675);
DOT 1 (-625 725);
DOT 1 (-625 625);
DOT 1 (-625 575);
DOT 1 (-775 975);
DOT 1 (-775 925);
DOT 1 (-775 875);
DOT 1 (-775 825);
DOT 1 (-775 775);
DOT 1 (-775 725);
DOT 1 (-775 625);
DOT 1 (-625 525);
DOT 1 (-775 525);
DOT 1 (-625 425);
DOT 1 (-625 475);
DOT 1 (-625 375);
DOT 1 (-625 325);
DOT 1 (-625 275);
DOT 1 (-625 175);
DOT 1 (-625 225);
DOT 1 (-625 125);
DOT 1 (-625 75);
DOT 1 (-625 25);
DOT 1 (-775 475);
DOT 1 (-775 425);
DOT 1 (-775 275);
DOT 1 (-775 325);
DOT 1 (-775 375);
DOT 1 (-775 175);
DOT 1 (-775 225);
DOT 1 (-775 125);
DOT 1 (-775 75);
DOT 1 (-775 25);
DOT 1 (-3675 3725);
DOT 1 (-3675 3675);
DOT 1 (-3675 3625);
DOT 1 (-3675 3575);
DOT 1 (-3675 3525);
DOT 1 (-3675 3475);
DOT 1 (-3675 3425);
DOT 1 (-3675 3375);
DOT 1 (-3675 3325);
DOT 1 (-3675 3275);
DOT 1 (-3675 3225);
DOT 1 (-3675 3175);
DOT 1 (-3675 3125);
DOT 1 (-3675 3075);
DOT 1 (-3675 3025);
DOT 1 (-3675 2975);
DOT 1 (-3675 2925);
DOT 1 (-3675 2875);
DOT 1 (-3675 2825);
DOT 1 (-3675 2725);
DOT 1 (-3675 2775);
DOT 1 (-3675 2675);
DOT 1 (-3675 2625);
DOT 1 (-3675 2575);
DOT 1 (-3675 2525);
DOT 1 (-3675 2475);
DOT 1 (-3675 2425);
DOT 1 (-3675 2375);
DOT 1 (-3675 2325);
DOT 1 (-3675 2225);
DOT 1 (-3675 2275);
DOT 1 (-3675 2175);
DOT 1 (-3675 2125);
DOT 1 (-3675 2075);
DOT 1 (-3675 2025);
DOT 1 (-3675 1975);
DOT 1 (-3675 1925);
DOT 1 (-3675 1875);
DOT 1 (-3675 1825);
DOT 1 (-3675 1775);
DOT 1 (-3675 1725);
DOT 1 (-3675 1675);
DOT 1 (-3675 1575);
DOT 1 (-3675 1625);
DOT 1 (-3675 1525);
DOT 1 (-3675 1475);
DOT 1 (-3675 1425);
DOT 1 (-3675 1325);
DOT 1 (-3675 1375);
DOT 1 (-3675 1275);
DOT 1 (-3675 1225);
DOT 1 (-3675 1175);
DOT 1 (-3675 1125);
DOT 1 (-3675 1075);
DOT 1 (-3675 1025);
DOT 1 (-3675 975);
DOT 1 (-3675 925);
DOT 1 (-3675 875);
DOT 1 (-3675 825);
DOT 1 (-3675 775);
DOT 1 (-3675 675);
DOT 1 (-3675 725);
DOT 1 (-3675 625);
DOT 1 (-3675 575);
DOT 1 (-3675 525);
DOT 1 (-3675 475);
DOT 1 (-3675 425);
DOT 1 (-3675 375);
DOT 1 (-3675 325);
DOT 1 (-3675 275);
DOT 1 (-3675 225);
DOT 1 (-3675 175);
DOT 1 (-3675 125);
DOT 1 (-3675 75);
DOT 1 (-3675 25);
DOT 1 (-625 -25);
DOT 1 (-625 -75);
DOT 1 (-625 -125);
DOT 1 (-625 -175);
DOT 1 (-775 -75);
DOT 1 (-775 -25);
DOT 1 (-775 -125);
DOT 1 (-775 -175);
DOT 1 (-3675 -25);
DOT 1 (-3675 -75);
DOT 1 (-3675 -125);
DOT 1 (-3675 -175);
DOT 1 (-625 1725);
DOT 1 (2275 1725);
DOT 1 (-775 575);
DOT 1 (-775 675);
DOT 1 (-775 1675);
DOT 1 (-775 1725);
DOT 1 (-625 1825);
DOT 1 (-625 1875);
DOT 1 (2275 3725);
DOT 1 (2400 3525);
DOT 1 (2400 1275);
DOT 1 (2275 1325);
QUIT
